FILE_TYPE = MACRO_DRAWING;
SET COLOR_WIRE YELLOW;
SET COLOR_PROP MONO;
SET COLOR_DOT WHITE;
SET COLOR_ARC YELLOW;
SET COLOR_BODY GREEN;
SET COLOR_NOTE MONO;
SET PROP_DISPLAY VALUE;
SET PAGE_NUMBER P146;
FORCEADD OFFPAGE..1
(-6500 4350);
FORCEPROP 2 LAST $XR0 199 
J 0
(-6752 4350);
DISPLAY 0.638298 (-6752 4350);
PAINT MONO (-6752 4350);
FORCEPROP 2 LAST $XR1 120 
J 0
(-6872 4350);
DISPLAY 0.638298 (-6872 4350);
PAINT MONO (-6872 4350);
FORCEPROP 2 LAST $XR2 170 
J 0
(-6992 4350);
DISPLAY 0.638298 (-6992 4350);
PAINT MONO (-6992 4350);
FORCEPROP 1 LAST COMMENT_BODY TRUE
J 0
(-6375 4250);
DISPLAY 0.872340 (-6375 4250);
PAINT GREEN (-6375 4250);
DISPLAY INVISIBLE (-6375 4250);
FORCEPROP 1 LAST OFFPAGE TRUE
J 0
(-6175 4225);
DISPLAY 0.872340 (-6175 4225);
PAINT GREEN (-6175 4225);
DISPLAY INVISIBLE (-6175 4225);
FORCEPROP 2 LAST BOM_COST SM_CONTROLLER
J 0
(-6050 4400);
PAINT MONO (-6050 4400);
DISPLAY INVISIBLE (-6050 4400);
FORCEPROP 2 LAST ROOM BMC
J 0
(-6750 4425);
DISPLAY 1.361702 (-6750 4425);
PAINT ORANGE (-6750 4425);
DISPLAY INVISIBLE (-6750 4425);
FORCEPROP 2 LAST PATH I103
J 0
(-6450 4425);
DISPLAY 1.021277 (-6450 4425);
PAINT ORANGE (-6450 4425);
DISPLAY INVISIBLE (-6450 4425);
FORCEPROP 2 LAST CDS_LIB mstr_standard
J 0
(-6500 4350);
PAINT MONO (-6500 4350);
DISPLAY INVISIBLE (-6500 4350);
FORCEADD AST2520A1-GP-GP..4
(-3875 4000);
FORCEPROP 1 LAST VALUE AST2520A1-GP-GP
J 0
(-5225 3150);
DISPLAY 0.617021 (-5225 3150);
PAINT GREEN (-5225 3150);
FORCEPROP 1 LAST LOCATION U25W4
J 0
(-5225 4825);
DISPLAY 0.617021 (-5225 4825);
PAINT GREEN (-5225 4825);
FORCEPROP 1 LAST PART_NUMBER 071.2520A.M001
J 0
(-3875 4000);
DISPLAY 0.617021 (-3875 4000);
PAINT GREEN (-3875 4000);
DISPLAY INVISIBLE (-3875 4000);
FORCEPROP 1 LAST PACK_TYPE ASIC2-GB1
J 0
(-3875 4000);
DISPLAY 0.617021 (-3875 4000);
PAINT GREEN (-3875 4000);
DISPLAY INVISIBLE (-3875 4000);
FORCEPROP 1 LAST PATH I104
J 0
(-3875 4000);
DISPLAY 0.617021 (-3875 4000);
PAINT GREEN (-3875 4000);
DISPLAY INVISIBLE (-3875 4000);
FORCEPROP 2 LAST CDS_LIB w_hdl
J 0
(-3875 4000);
PAINT MONO (-3875 4000);
DISPLAY INVISIBLE (-3875 4000);
FORCEPROP 1 LAST CDS_LMAN_SYM_OUTLINE -1350,800,1350,-800
J 0
(-3875 4000);
DISPLAY 0.468085 (-3875 4000);
PAINT GREEN (-3875 4000);
DISPLAY INVISIBLE (-3875 4000);
FORCEADD AST2520A1-GP-GP..5
(-4025 1850);
FORCEPROP 1 LAST VALUE AST2520A1-GP-GP
J 0
(-5350 850);
DISPLAY 0.617021 (-5350 850);
PAINT GREEN (-5350 850);
FORCEPROP 1 LAST LOCATION U25W4
J 0
(-5350 2825);
DISPLAY 0.617021 (-5350 2825);
PAINT GREEN (-5350 2825);
FORCEPROP 1 LAST CDS_LMAN_SYM_OUTLINE -1325,950,1325,-950
J 0
(-4025 1850);
DISPLAY 0.468085 (-4025 1850);
PAINT GREEN (-4025 1850);
DISPLAY INVISIBLE (-4025 1850);
FORCEPROP 1 LAST PACK_TYPE ASIC2-GB1
J 0
(-4025 1850);
DISPLAY 0.617021 (-4025 1850);
PAINT GREEN (-4025 1850);
DISPLAY INVISIBLE (-4025 1850);
FORCEPROP 1 LAST PATH I105
J 0
(-4025 1850);
DISPLAY 0.617021 (-4025 1850);
PAINT GREEN (-4025 1850);
DISPLAY INVISIBLE (-4025 1850);
FORCEPROP 1 LAST PART_NUMBER 071.2520A.M001
J 0
(-4025 1850);
DISPLAY 0.617021 (-4025 1850);
PAINT GREEN (-4025 1850);
DISPLAY INVISIBLE (-4025 1850);
FORCEPROP 2 LAST CDS_LIB w_hdl
J 0
(-4025 1850);
PAINT MONO (-4025 1850);
DISPLAY INVISIBLE (-4025 1850);
FORCEADD OFFPAGE..1
(-7100 2600);
FORCEPROP 2 LAST $XR0 249 
J 0
(-7352 2600);
DISPLAY 0.638298 (-7352 2600);
PAINT MONO (-7352 2600);
FORCEPROP 1 LAST COMMENT_BODY TRUE
J 0
(-6975 2500);
DISPLAY 0.872340 (-6975 2500);
PAINT GREEN (-6975 2500);
DISPLAY INVISIBLE (-6975 2500);
FORCEPROP 1 LAST OFFPAGE TRUE
J 0
(-6775 2475);
DISPLAY 0.872340 (-6775 2475);
PAINT GREEN (-6775 2475);
DISPLAY INVISIBLE (-6775 2475);
FORCEPROP 2 LAST CDS_LIB mstr_standard
J 0
(-7100 2600);
PAINT ORANGE (-7100 2600);
DISPLAY INVISIBLE (-7100 2600);
FORCEPROP 2 LAST PATH I107
J 0
(-7350 2650);
DISPLAY 1.021277 (-7350 2650);
PAINT ORANGE (-7350 2650);
DISPLAY INVISIBLE (-7350 2650);
FORCEADD OFFPAGE..5
R 2
(-1250 2550);
FORCEPROP 2 LAST $XR0 119 
J 0
(-1061 2550);
DISPLAY 0.638298 (-1061 2550);
PAINT MONO (-1061 2550);
FORCEPROP 2 LAST $XR1 151 
J 0
(-941 2550);
DISPLAY 0.638298 (-941 2550);
PAINT MONO (-941 2550);
FORCEPROP 1 LAST COMMENT_BODY TRUE
J 2
(-1350 2475);
DISPLAY 0.872340 (-1350 2475);
PAINT GREEN (-1350 2475);
DISPLAY INVISIBLE (-1350 2475);
FORCEPROP 1 LAST OFFPAGE TRUE
J 2
(-1575 2425);
DISPLAY 0.872340 (-1575 2425);
PAINT GREEN (-1575 2425);
DISPLAY INVISIBLE (-1575 2425);
FORCEPROP 2 LAST CDS_LIB mstr_standard
J 2
(-1250 2550);
PAINT MONO (-1250 2550);
DISPLAY INVISIBLE (-1250 2550);
FORCEPROP 2 LAST PATH I108
J 2
(-975 2600);
DISPLAY 1.021277 (-975 2600);
PAINT ORANGE (-975 2600);
DISPLAY INVISIBLE (-975 2600);
FORCEADD OFFPAGE..4
R 2
(-6900 1050);
FORCEPROP 2 LAST $XR0 133 
J 0
(-7152 1050);
DISPLAY 0.638298 (-7152 1050);
PAINT MONO (-7152 1050);
FORCEPROP 2 LAST $XR1 199 
J 0
(-7272 1050);
DISPLAY 0.638298 (-7272 1050);
PAINT MONO (-7272 1050);
FORCEPROP 2 LAST $XR2 119 
J 0
(-7392 1050);
DISPLAY 0.638298 (-7392 1050);
PAINT MONO (-7392 1050);
FORCEPROP 2 LAST CDS_LIB mstr_standard
J 2
(-6900 1050);
PAINT MONO (-6900 1050);
DISPLAY INVISIBLE (-6900 1050);
FORCEPROP 2 LAST PATH I110
J 2
(-7375 1100);
DISPLAY 1.021277 (-7375 1100);
PAINT ORANGE (-7375 1100);
DISPLAY INVISIBLE (-7375 1100);
FORCEPROP 1 LAST OFFPAGE TRUE
J 2
(-7225 925);
DISPLAY 0.872340 (-7225 925);
PAINT GREEN (-7225 925);
DISPLAY INVISIBLE (-7225 925);
FORCEPROP 1 LAST COMMENT_BODY TRUE
J 2
(-6875 950);
DISPLAY 0.872340 (-6875 950);
PAINT GREEN (-6875 950);
DISPLAY INVISIBLE (-6875 950);
FORCEADD OFFPAGE..1
(-6500 4600);
FORCEPROP 2 LAST $XR0 139 
J 0
(-6752 4600);
DISPLAY 0.638298 (-6752 4600);
PAINT MONO (-6752 4600);
FORCEPROP 2 LAST $XR1 119 
J 0
(-6872 4600);
DISPLAY 0.638298 (-6872 4600);
PAINT MONO (-6872 4600);
FORCEPROP 1 LAST COMMENT_BODY TRUE
J 0
(-6375 4500);
DISPLAY 0.872340 (-6375 4500);
PAINT GREEN (-6375 4500);
DISPLAY INVISIBLE (-6375 4500);
FORCEPROP 1 LAST OFFPAGE TRUE
J 0
(-6175 4475);
DISPLAY 0.872340 (-6175 4475);
PAINT GREEN (-6175 4475);
DISPLAY INVISIBLE (-6175 4475);
FORCEPROP 2 LAST PATH I111
J 0
(-6750 4650);
DISPLAY 1.021277 (-6750 4650);
PAINT ORANGE (-6750 4650);
DISPLAY INVISIBLE (-6750 4650);
FORCEPROP 2 LAST BOM_COST SM_CONTROLLER
J 0
(-6050 4650);
PAINT MONO (-6050 4650);
DISPLAY INVISIBLE (-6050 4650);
FORCEPROP 2 LAST ROOM BMC
J 0
(-6750 4675);
DISPLAY 1.361702 (-6750 4675);
PAINT ORANGE (-6750 4675);
DISPLAY INVISIBLE (-6750 4675);
FORCEPROP 2 LAST CDS_LIB mstr_standard
J 0
(-6500 4600);
PAINT ORANGE (-6500 4600);
DISPLAY INVISIBLE (-6500 4600);
FORCEADD OFFPAGE..5
(-6500 4550);
FORCEPROP 2 LAST $XR0 137 
J 0
(-6755 4550);
DISPLAY 0.638298 (-6755 4550);
PAINT MONO (-6755 4550);
FORCEPROP 2 LAST $XR1 200 
J 0
(-6875 4550);
DISPLAY 0.638298 (-6875 4550);
PAINT MONO (-6875 4550);
FORCEPROP 1 LAST COMMENT_BODY TRUE
J 0
(-6400 4475);
DISPLAY 0.872340 (-6400 4475);
PAINT GREEN (-6400 4475);
DISPLAY INVISIBLE (-6400 4475);
FORCEPROP 1 LAST OFFPAGE TRUE
J 0
(-6175 4425);
DISPLAY 0.872340 (-6175 4425);
PAINT GREEN (-6175 4425);
DISPLAY INVISIBLE (-6175 4425);
FORCEPROP 2 LAST PATH I114
J 0
(-6750 4600);
DISPLAY 1.021277 (-6750 4600);
PAINT ORANGE (-6750 4600);
DISPLAY INVISIBLE (-6750 4600);
FORCEPROP 2 LAST CDS_LIB mstr_standard
J 0
(-6500 4550);
PAINT MONO (-6500 4550);
DISPLAY INVISIBLE (-6500 4550);
FORCEADD OFFPAGE..1
(-6500 4450);
FORCEPROP 2 LAST $XR0 133 
J 0
(-6752 4450);
DISPLAY 0.638298 (-6752 4450);
PAINT MONO (-6752 4450);
FORCEPROP 2 LAST $XR1 249 
J 0
(-6872 4450);
DISPLAY 0.638298 (-6872 4450);
PAINT MONO (-6872 4450);
FORCEPROP 2 LAST $XR2 119 
J 0
(-6992 4450);
DISPLAY 0.638298 (-6992 4450);
PAINT MONO (-6992 4450);
FORCEPROP 1 LAST COMMENT_BODY TRUE
J 0
(-6375 4350);
DISPLAY 0.872340 (-6375 4350);
PAINT GREEN (-6375 4350);
DISPLAY INVISIBLE (-6375 4350);
FORCEPROP 1 LAST OFFPAGE TRUE
J 0
(-6175 4325);
DISPLAY 0.872340 (-6175 4325);
PAINT GREEN (-6175 4325);
DISPLAY INVISIBLE (-6175 4325);
FORCEPROP 2 LAST PATH I115
J 0
(-6750 4500);
DISPLAY 1.021277 (-6750 4500);
PAINT ORANGE (-6750 4500);
DISPLAY INVISIBLE (-6750 4500);
FORCEPROP 2 LAST CDS_LIB mstr_standard
J 0
(-6500 4450);
PAINT MONO (-6500 4450);
DISPLAY INVISIBLE (-6500 4450);
FORCEADD OFFPAGE..4
R 2
(-6500 3950);
FORCEPROP 2 LAST $XR0 218 
J 0
(-6752 3950);
DISPLAY 0.638298 (-6752 3950);
PAINT MONO (-6752 3950);
FORCEPROP 2 LAST $XR1 94 
J 0
(-6842 3950);
DISPLAY 0.638298 (-6842 3950);
PAINT MONO (-6842 3950);
FORCEPROP 2 LAST $XR2 119 
J 0
(-6962 3950);
DISPLAY 0.638298 (-6962 3950);
PAINT MONO (-6962 3950);
FORCEPROP 1 LAST COMMENT_BODY TRUE
J 2
(-6475 3850);
DISPLAY 0.872340 (-6475 3850);
PAINT GREEN (-6475 3850);
DISPLAY INVISIBLE (-6475 3850);
FORCEPROP 1 LAST OFFPAGE TRUE
J 2
(-6825 3825);
DISPLAY 0.872340 (-6825 3825);
PAINT GREEN (-6825 3825);
DISPLAY INVISIBLE (-6825 3825);
FORCEPROP 2 LAST CDS_LIB mstr_standard
J 2
(-6500 3950);
PAINT MONO (-6500 3950);
DISPLAY INVISIBLE (-6500 3950);
FORCEPROP 2 LAST PATH I116
J 2
(-6900 4000);
DISPLAY 1.021277 (-6900 4000);
PAINT ORANGE (-6900 4000);
DISPLAY INVISIBLE (-6900 4000);
FORCEADD OFFPAGE..2
R 2
(-6500 3850);
FORCEPROP 2 LAST $XR0 119 
J 0
(-6755 3850);
DISPLAY 0.638298 (-6755 3850);
PAINT MONO (-6755 3850);
FORCEPROP 2 LAST $XR1 157 
J 0
(-6875 3850);
DISPLAY 0.638298 (-6875 3850);
PAINT MONO (-6875 3850);
FORCEPROP 2 LAST $XR2 190 
J 0
(-6995 3850);
DISPLAY 0.638298 (-6995 3850);
PAINT MONO (-6995 3850);
FORCEPROP 1 LAST COMMENT_BODY TRUE
J 2
(-6455 3755);
DISPLAY 0.872340 (-6455 3755);
PAINT GREEN (-6455 3755);
DISPLAY INVISIBLE (-6455 3755);
FORCEPROP 1 LAST OFFPAGE TRUE
J 2
(-6825 3725);
DISPLAY 0.872340 (-6825 3725);
PAINT GREEN (-6825 3725);
DISPLAY INVISIBLE (-6825 3725);
FORCEPROP 2 LAST PATH I117
J 2
(-6675 3925);
DISPLAY 1.021277 (-6675 3925);
PAINT ORANGE (-6675 3925);
DISPLAY INVISIBLE (-6675 3925);
FORCEPROP 2 LAST CDS_LIB mstr_standard
J 2
(-6500 3850);
PAINT MONO (-6500 3850);
DISPLAY INVISIBLE (-6500 3850);
FORCEADD OFFPAGE..1
R 2
(-1250 1600);
FORCEPROP 2 LAST $XR0 168 
J 0
(-1064 1600);
DISPLAY 0.638298 (-1064 1600);
PAINT MONO (-1064 1600);
FORCEPROP 2 LAST $XR1 120 
J 0
(-944 1600);
DISPLAY 0.638298 (-944 1600);
PAINT MONO (-944 1600);
FORCEPROP 1 LAST COMMENT_BODY TRUE
J 2
(-1375 1500);
DISPLAY 0.872340 (-1375 1500);
PAINT GREEN (-1375 1500);
DISPLAY INVISIBLE (-1375 1500);
FORCEPROP 1 LAST OFFPAGE TRUE
J 2
(-1575 1475);
DISPLAY 0.872340 (-1575 1475);
PAINT GREEN (-1575 1475);
DISPLAY INVISIBLE (-1575 1475);
FORCEPROP 2 LAST PATH I119
J 2
(-975 1650);
DISPLAY 1.021277 (-975 1650);
PAINT ORANGE (-975 1650);
DISPLAY INVISIBLE (-975 1650);
FORCEPROP 2 LAST CDS_LIB mstr_standard
J 2
(-1250 1600);
PAINT MONO (-1250 1600);
DISPLAY INVISIBLE (-1250 1600);
FORCEADD OFFPAGE..5
R 2
(-750 2050);
FORCEPROP 2 LAST $XR0 162 
J 0
(-561 2050);
DISPLAY 0.638298 (-561 2050);
PAINT MONO (-561 2050);
FORCEPROP 1 LAST COMMENT_BODY TRUE
J 2
(-850 1975);
DISPLAY 0.872340 (-850 1975);
PAINT GREEN (-850 1975);
DISPLAY INVISIBLE (-850 1975);
FORCEPROP 1 LAST OFFPAGE TRUE
J 2
(-1075 1925);
DISPLAY 0.872340 (-1075 1925);
PAINT GREEN (-1075 1925);
DISPLAY INVISIBLE (-1075 1925);
FORCEPROP 2 LAST PATH I120
J 2
(-475 2100);
DISPLAY 1.021277 (-475 2100);
PAINT ORANGE (-475 2100);
DISPLAY INVISIBLE (-475 2100);
FORCEPROP 2 LAST CDS_LIB mstr_standard
J 2
(-750 2050);
PAINT ORANGE (-750 2050);
DISPLAY INVISIBLE (-750 2050);
FORCEADD RES..1
(-1450 2050);
FORCEPROP 1 LAST TOLERANCE 1.0%
J 0
(-1525 2175);
DISPLAY 0.617021 (-1525 2175);
PAINT SKYBLUE (-1525 2175);
FORCEPROP 1 LAST MATERIAL CHIP
J 0
(-1525 2125);
DISPLAY 0.617021 (-1525 2125);
PAINT SKYBLUE (-1525 2125);
FORCEPROP 1 LASTPIN (-1550 2050) $PN 1
J 0
(-1538 2062);
DISPLAY 0.617021 (-1538 2062);
PAINT ORANGE (-1538 2062);
FORCEPROP 1 LAST VALUE 22.1
J 2
(-1425 2225);
DISPLAY 0.617021 (-1425 2225);
PAINT SKYBLUE (-1425 2225);
FORCEPROP 1 LAST LOCATION R25W78
J 0
(-1525 2275);
DISPLAY 0.617021 (-1525 2275);
PAINT AQUA (-1525 2275);
FORCEPROP 1 LASTPIN (-1350 2050) $PN 2
J 0
(-1388 2062);
DISPLAY 0.617021 (-1388 2062);
PAINT ORANGE (-1388 2062);
FORCEPROP 1 LAST PART_NUMBER G21796-250
J 0
(-1350 2175);
DISPLAY 0.638298 (-1350 2175);
PAINT BLUE (-1350 2175);
FORCEPROP 1 LAST WATTAGE 1/16W
J 0
(-1350 2225);
DISPLAY 0.638298 (-1350 2225);
PAINT SKYBLUE (-1350 2225);
FORCEPROP 1 LAST PACK_TYPE 0402
J 0
(-1325 2275);
DISPLAY 0.638298 (-1325 2275);
PAINT SKYBLUE (-1325 2275);
FORCEPROP 1 LAST PATH I123
J 0
(-1500 2200);
DISPLAY 0.978723 (-1500 2200);
PAINT WHITE (-1500 2200);
DISPLAY INVISIBLE (-1500 2200);
FORCEPROP 0 LAST CDS_SEC 1
J 0
(-1525 2050);
PAINT MONO (-1525 2050);
DISPLAY INVISIBLE (-1525 2050);
FORCEPROP 2 LAST CDS_LOCATION R25W78
J 0
(-1475 2075);
DISPLAY 0.617021 (-1475 2075);
PAINT AQUA (-1475 2075);
DISPLAY INVISIBLE (-1475 2075);
FORCEPROP 2 LAST CDS_LIB mstr_discrete
J 0
(-1450 2050);
PAINT ORANGE (-1450 2050);
DISPLAY INVISIBLE (-1450 2050);
FORCEPROP 2 LAST SEC_TYPE 0402
J 0
(-1500 2250);
DISPLAY 1.021277 (-1500 2250);
PAINT ORANGE (-1500 2250);
DISPLAY INVISIBLE (-1500 2250);
FORCEPROP 2 LAST SEC 1
J 0
(-1500 2250);
DISPLAY 0.680851 (-1500 2250);
PAINT MONO (-1500 2250);
DISPLAY INVISIBLE (-1500 2250);
FORCEPROP 0 LAST ROOM BMC
J 0
(-1200 2175);
DISPLAY 1.021277 (-1200 2175);
PAINT ORANGE (-1200 2175);
DISPLAY INVISIBLE (-1200 2175);
FORCEPROP 0 LAST BOM_COST SM_CONTROLLER
J 0
(-1200 2275);
DISPLAY 1.021277 (-1200 2275);
PAINT ORANGE (-1200 2275);
DISPLAY INVISIBLE (-1200 2275);
FORCEADD OFFPAGE..5
R 2
(-750 2000);
FORCEPROP 2 LAST $XR0 157 
J 0
(-561 2000);
DISPLAY 0.638298 (-561 2000);
PAINT MONO (-561 2000);
FORCEPROP 2 LAST $XR1 181 
J 0
(-441 2000);
DISPLAY 0.638298 (-441 2000);
PAINT MONO (-441 2000);
FORCEPROP 2 LAST $XR2 120 
J 0
(-321 2000);
DISPLAY 0.638298 (-321 2000);
PAINT MONO (-321 2000);
FORCEPROP 1 LAST COMMENT_BODY TRUE
J 2
(-850 1925);
DISPLAY 0.872340 (-850 1925);
PAINT GREEN (-850 1925);
DISPLAY INVISIBLE (-850 1925);
FORCEPROP 1 LAST OFFPAGE TRUE
J 2
(-1075 1875);
DISPLAY 0.872340 (-1075 1875);
PAINT GREEN (-1075 1875);
DISPLAY INVISIBLE (-1075 1875);
FORCEPROP 2 LAST PATH I124
J 2
(-500 2050);
DISPLAY 1.021277 (-500 2050);
PAINT ORANGE (-500 2050);
DISPLAY INVISIBLE (-500 2050);
FORCEPROP 2 LAST CDS_LIB mstr_standard
J 2
(-750 2000);
PAINT MONO (-750 2000);
DISPLAY INVISIBLE (-750 2000);
FORCEADD OFFPAGE..5
(-6500 3750);
FORCEPROP 2 LAST $XR0 150 
J 0
(-6755 3750);
DISPLAY 0.638298 (-6755 3750);
PAINT MONO (-6755 3750);
FORCEPROP 1 LAST COMMENT_BODY TRUE
J 0
(-6400 3675);
DISPLAY 0.872340 (-6400 3675);
PAINT GREEN (-6400 3675);
DISPLAY INVISIBLE (-6400 3675);
FORCEPROP 1 LAST OFFPAGE TRUE
J 0
(-6175 3625);
DISPLAY 0.872340 (-6175 3625);
PAINT GREEN (-6175 3625);
DISPLAY INVISIBLE (-6175 3625);
FORCEPROP 2 LAST BOM_COST SM_CONTROLLER
J 0
(-6050 3800);
PAINT MONO (-6050 3800);
DISPLAY INVISIBLE (-6050 3800);
FORCEPROP 2 LAST ROOM BMC
J 0
(-6750 3825);
DISPLAY 1.361702 (-6750 3825);
PAINT ORANGE (-6750 3825);
DISPLAY INVISIBLE (-6750 3825);
FORCEPROP 2 LAST CDS_LIB mstr_standard
J 0
(-6500 3750);
PAINT MONO (-6500 3750);
DISPLAY INVISIBLE (-6500 3750);
FORCEPROP 2 LAST PATH I127
J 0
(-6775 3800);
DISPLAY 1.021277 (-6775 3800);
PAINT ORANGE (-6775 3800);
DISPLAY INVISIBLE (-6775 3800);
FORCEADD OFFPAGE..1
(-6500 4300);
FORCEPROP 2 LAST $XR0 55 
J 0
(-6751 4300);
DISPLAY 0.638298 (-6751 4300);
PAINT MONO (-6751 4300);
FORCEPROP 2 LAST $XR1 112 
J 0
(-6871 4300);
DISPLAY 0.638298 (-6871 4300);
PAINT MONO (-6871 4300);
FORCEPROP 2 LAST $XR2 118 
J 0
(-6991 4300);
DISPLAY 0.638298 (-6991 4300);
PAINT MONO (-6991 4300);
FORCEPROP 2 LAST $XR3 190 
J 0
(-7111 4300);
DISPLAY 0.638298 (-7111 4300);
PAINT MONO (-7111 4300);
FORCEPROP 1 LAST COMMENT_BODY TRUE
J 0
(-6375 4200);
DISPLAY 0.872340 (-6375 4200);
PAINT GREEN (-6375 4200);
DISPLAY INVISIBLE (-6375 4200);
FORCEPROP 1 LAST OFFPAGE TRUE
J 0
(-6175 4175);
DISPLAY 0.872340 (-6175 4175);
PAINT GREEN (-6175 4175);
DISPLAY INVISIBLE (-6175 4175);
FORCEPROP 2 LAST ROOM BMC
J 0
(-6750 4375);
DISPLAY 1.361702 (-6750 4375);
PAINT ORANGE (-6750 4375);
DISPLAY INVISIBLE (-6750 4375);
FORCEPROP 2 LAST BOM_COST SM_CONTROLLER
J 0
(-6050 4350);
PAINT MONO (-6050 4350);
DISPLAY INVISIBLE (-6050 4350);
FORCEPROP 2 LAST CDS_LIB mstr_standard
J 0
(-6500 4300);
PAINT MONO (-6500 4300);
DISPLAY INVISIBLE (-6500 4300);
FORCEPROP 2 LAST PATH I128
J 0
(-6700 4350);
DISPLAY 1.021277 (-6700 4350);
PAINT ORANGE (-6700 4350);
DISPLAY INVISIBLE (-6700 4350);
FORCEADD OFFPAGE..1
(-6500 3600);
FORCEPROP 2 LAST $XR0 150 
J 0
(-6752 3600);
DISPLAY 0.638298 (-6752 3600);
PAINT MONO (-6752 3600);
FORCEPROP 1 LAST COMMENT_BODY TRUE
J 0
(-6375 3500);
DISPLAY 0.872340 (-6375 3500);
PAINT GREEN (-6375 3500);
DISPLAY INVISIBLE (-6375 3500);
FORCEPROP 1 LAST OFFPAGE TRUE
J 0
(-6175 3475);
DISPLAY 0.872340 (-6175 3475);
PAINT GREEN (-6175 3475);
DISPLAY INVISIBLE (-6175 3475);
FORCEPROP 2 LAST CDS_LIB mstr_standard
J 0
(-6500 3600);
PAINT MONO (-6500 3600);
DISPLAY INVISIBLE (-6500 3600);
FORCEPROP 2 LAST PATH I135
J 0
(-6450 3675);
DISPLAY 1.021277 (-6450 3675);
PAINT ORANGE (-6450 3675);
DISPLAY INVISIBLE (-6450 3675);
FORCEPROP 2 LAST BOM_COST SM_CONTROLLER
J 0
(-6050 3650);
PAINT MONO (-6050 3650);
DISPLAY INVISIBLE (-6050 3650);
FORCEPROP 2 LAST ROOM BMC
J 0
(-6750 3675);
DISPLAY 1.361702 (-6750 3675);
PAINT ORANGE (-6750 3675);
DISPLAY INVISIBLE (-6750 3675);
FORCEADD OFFPAGE..1
(-6500 3700);
FORCEPROP 2 LAST $XR0 150 
J 0
(-6752 3700);
DISPLAY 0.638298 (-6752 3700);
PAINT MONO (-6752 3700);
FORCEPROP 1 LAST COMMENT_BODY TRUE
J 0
(-6375 3600);
DISPLAY 0.872340 (-6375 3600);
PAINT GREEN (-6375 3600);
DISPLAY INVISIBLE (-6375 3600);
FORCEPROP 1 LAST OFFPAGE TRUE
J 0
(-6175 3575);
DISPLAY 0.872340 (-6175 3575);
PAINT GREEN (-6175 3575);
DISPLAY INVISIBLE (-6175 3575);
FORCEPROP 2 LAST CDS_LIB mstr_standard
J 0
(-6500 3700);
PAINT MONO (-6500 3700);
DISPLAY INVISIBLE (-6500 3700);
FORCEPROP 2 LAST PATH I138
J 0
(-6450 3775);
DISPLAY 1.021277 (-6450 3775);
PAINT ORANGE (-6450 3775);
DISPLAY INVISIBLE (-6450 3775);
FORCEPROP 2 LAST ROOM BMC
J 0
(-6750 3775);
DISPLAY 1.361702 (-6750 3775);
PAINT ORANGE (-6750 3775);
DISPLAY INVISIBLE (-6750 3775);
FORCEPROP 2 LAST BOM_COST SM_CONTROLLER
J 0
(-6050 3750);
PAINT MONO (-6050 3750);
DISPLAY INVISIBLE (-6050 3750);
FORCEADD OFFPAGE..1
(-6500 4050);
FORCEPROP 2 LAST $XR0 150 
J 0
(-6752 4050);
DISPLAY 0.638298 (-6752 4050);
PAINT MONO (-6752 4050);
FORCEPROP 1 LAST COMMENT_BODY TRUE
J 0
(-6375 3950);
DISPLAY 0.872340 (-6375 3950);
PAINT GREEN (-6375 3950);
DISPLAY INVISIBLE (-6375 3950);
FORCEPROP 1 LAST OFFPAGE TRUE
J 0
(-6175 3925);
DISPLAY 0.872340 (-6175 3925);
PAINT GREEN (-6175 3925);
DISPLAY INVISIBLE (-6175 3925);
FORCEPROP 2 LAST ROOM BMC
J 0
(-6750 4125);
DISPLAY 1.361702 (-6750 4125);
PAINT ORANGE (-6750 4125);
DISPLAY INVISIBLE (-6750 4125);
FORCEPROP 2 LAST BOM_COST SM_CONTROLLER
J 0
(-6050 4100);
PAINT MONO (-6050 4100);
DISPLAY INVISIBLE (-6050 4100);
FORCEPROP 2 LAST PATH I139
J 0
(-6450 4125);
DISPLAY 1.021277 (-6450 4125);
PAINT ORANGE (-6450 4125);
DISPLAY INVISIBLE (-6450 4125);
FORCEPROP 2 LAST CDS_LIB mstr_standard
J 0
(-6500 4050);
PAINT MONO (-6500 4050);
DISPLAY INVISIBLE (-6500 4050);
FORCEADD OFFPAGE..1
(-6500 4100);
FORCEPROP 2 LAST $XR0 150 
J 0
(-6752 4100);
DISPLAY 0.638298 (-6752 4100);
PAINT MONO (-6752 4100);
FORCEPROP 1 LAST COMMENT_BODY TRUE
J 0
(-6375 4000);
DISPLAY 0.872340 (-6375 4000);
PAINT GREEN (-6375 4000);
DISPLAY INVISIBLE (-6375 4000);
FORCEPROP 1 LAST OFFPAGE TRUE
J 0
(-6175 3975);
DISPLAY 0.872340 (-6175 3975);
PAINT GREEN (-6175 3975);
DISPLAY INVISIBLE (-6175 3975);
FORCEPROP 2 LAST ROOM BMC
J 0
(-6750 4175);
DISPLAY 1.361702 (-6750 4175);
PAINT ORANGE (-6750 4175);
DISPLAY INVISIBLE (-6750 4175);
FORCEPROP 2 LAST BOM_COST SM_CONTROLLER
J 0
(-6050 4150);
PAINT MONO (-6050 4150);
DISPLAY INVISIBLE (-6050 4150);
FORCEPROP 2 LAST PATH I140
J 0
(-6450 4175);
DISPLAY 1.021277 (-6450 4175);
PAINT ORANGE (-6450 4175);
DISPLAY INVISIBLE (-6450 4175);
FORCEPROP 2 LAST CDS_LIB mstr_standard
J 0
(-6500 4100);
PAINT MONO (-6500 4100);
DISPLAY INVISIBLE (-6500 4100);
FORCEADD OFFPAGE..1
(-6500 4150);
FORCEPROP 2 LAST $XR0 150 
J 0
(-6752 4150);
DISPLAY 0.638298 (-6752 4150);
PAINT MONO (-6752 4150);
FORCEPROP 1 LAST COMMENT_BODY TRUE
J 0
(-6375 4050);
DISPLAY 0.872340 (-6375 4050);
PAINT GREEN (-6375 4050);
DISPLAY INVISIBLE (-6375 4050);
FORCEPROP 1 LAST OFFPAGE TRUE
J 0
(-6175 4025);
DISPLAY 0.872340 (-6175 4025);
PAINT GREEN (-6175 4025);
DISPLAY INVISIBLE (-6175 4025);
FORCEPROP 2 LAST CDS_LIB mstr_standard
J 0
(-6500 4150);
PAINT MONO (-6500 4150);
DISPLAY INVISIBLE (-6500 4150);
FORCEPROP 2 LAST PATH I141
J 0
(-6450 4225);
DISPLAY 1.021277 (-6450 4225);
PAINT ORANGE (-6450 4225);
DISPLAY INVISIBLE (-6450 4225);
FORCEPROP 2 LAST BOM_COST SM_CONTROLLER
J 0
(-6050 4200);
PAINT MONO (-6050 4200);
DISPLAY INVISIBLE (-6050 4200);
FORCEPROP 2 LAST ROOM BMC
J 0
(-6750 4225);
DISPLAY 1.361702 (-6750 4225);
PAINT ORANGE (-6750 4225);
DISPLAY INVISIBLE (-6750 4225);
FORCEADD OFFPAGE..2
R 2
(-7100 2400);
FORCEPROP 2 LAST $XR0 137 
J 0
(-7355 2400);
DISPLAY 0.638298 (-7355 2400);
PAINT MONO (-7355 2400);
FORCEPROP 2 LAST $XR1 246 
J 0
(-7475 2400);
DISPLAY 0.638298 (-7475 2400);
PAINT MONO (-7475 2400);
FORCEPROP 1 LAST COMMENT_BODY TRUE
J 2
(-7055 2305);
DISPLAY 0.872340 (-7055 2305);
PAINT GREEN (-7055 2305);
DISPLAY INVISIBLE (-7055 2305);
FORCEPROP 1 LAST OFFPAGE TRUE
J 2
(-7425 2275);
DISPLAY 0.872340 (-7425 2275);
PAINT GREEN (-7425 2275);
DISPLAY INVISIBLE (-7425 2275);
FORCEPROP 2 LAST CDS_LIB mstr_standard
J 2
(-7100 2400);
PAINT MONO (-7100 2400);
DISPLAY INVISIBLE (-7100 2400);
FORCEPROP 2 LAST PATH I142
J 2
(-7300 2450);
DISPLAY 1.021277 (-7300 2450);
PAINT ORANGE (-7300 2450);
DISPLAY INVISIBLE (-7300 2450);
FORCEADD OFFPAGE..4
R 2
(-6900 1100);
FORCEPROP 2 LAST $XR0 133 
J 0
(-7152 1100);
DISPLAY 0.638298 (-7152 1100);
PAINT MONO (-7152 1100);
FORCEPROP 2 LAST $XR1 250 
J 0
(-7272 1100);
DISPLAY 0.638298 (-7272 1100);
PAINT MONO (-7272 1100);
FORCEPROP 2 LAST $XR2 119 
J 0
(-7392 1100);
DISPLAY 0.638298 (-7392 1100);
PAINT MONO (-7392 1100);
FORCEPROP 2 LAST PATH I143
J 0
(-6850 1175);
DISPLAY 1.021277 (-6850 1175);
PAINT ORANGE (-6850 1175);
DISPLAY INVISIBLE (-6850 1175);
FORCEPROP 2 LAST CDS_LIB mstr_standard
J 0
(-6900 1100);
PAINT MONO (-6900 1100);
DISPLAY INVISIBLE (-6900 1100);
FORCEPROP 1 LAST OFFPAGE TRUE
J 2
(-7225 975);
DISPLAY 0.872340 (-7225 975);
PAINT GREEN (-7225 975);
DISPLAY INVISIBLE (-7225 975);
FORCEPROP 1 LAST COMMENT_BODY TRUE
J 2
(-6875 1000);
DISPLAY 0.872340 (-6875 1000);
PAINT GREEN (-6875 1000);
DISPLAY INVISIBLE (-6875 1000);
FORCEADD OFFPAGE..5
(-6500 3550);
FORCEPROP 2 LAST $XR0 247 
J 0
(-6755 3550);
DISPLAY 0.638298 (-6755 3550);
PAINT MONO (-6755 3550);
FORCEPROP 1 LAST COMMENT_BODY TRUE
J 0
(-6400 3475);
DISPLAY 0.872340 (-6400 3475);
PAINT GREEN (-6400 3475);
DISPLAY INVISIBLE (-6400 3475);
FORCEPROP 1 LAST OFFPAGE TRUE
J 0
(-6175 3425);
DISPLAY 0.872340 (-6175 3425);
PAINT GREEN (-6175 3425);
DISPLAY INVISIBLE (-6175 3425);
FORCEPROP 2 LAST CDS_LIB mstr_standard
J 0
(-6500 3550);
PAINT MONO (-6500 3550);
DISPLAY INVISIBLE (-6500 3550);
FORCEPROP 2 LAST PATH I144
J 0
(-6775 3600);
DISPLAY 1.021277 (-6775 3600);
PAINT ORANGE (-6775 3600);
DISPLAY INVISIBLE (-6775 3600);
FORCEADD OFFPAGE..5
(-6500 4400);
FORCEPROP 2 LAST $XR0 120 
J 0
(-6755 4400);
DISPLAY 0.638298 (-6755 4400);
PAINT MONO (-6755 4400);
FORCEPROP 2 LAST $XR1 133 
J 0
(-6875 4400);
DISPLAY 0.638298 (-6875 4400);
PAINT MONO (-6875 4400);
FORCEPROP 2 LAST $XR2 175 
J 0
(-6995 4400);
DISPLAY 0.638298 (-6995 4400);
PAINT MONO (-6995 4400);
FORCEPROP 1 LAST COMMENT_BODY TRUE
J 0
(-6400 4325);
DISPLAY 0.872340 (-6400 4325);
PAINT GREEN (-6400 4325);
DISPLAY INVISIBLE (-6400 4325);
FORCEPROP 1 LAST OFFPAGE TRUE
J 0
(-6175 4275);
DISPLAY 0.872340 (-6175 4275);
PAINT GREEN (-6175 4275);
DISPLAY INVISIBLE (-6175 4275);
FORCEPROP 2 LAST PATH I145
J 0
(-6775 4450);
DISPLAY 1.021277 (-6775 4450);
PAINT ORANGE (-6775 4450);
DISPLAY INVISIBLE (-6775 4450);
FORCEPROP 2 LAST BOM_COST SM_CONTROLLER
J 0
(-6050 4450);
PAINT MONO (-6050 4450);
DISPLAY INVISIBLE (-6050 4450);
FORCEPROP 2 LAST ROOM BMC
J 0
(-6750 4475);
DISPLAY 1.361702 (-6750 4475);
PAINT ORANGE (-6750 4475);
DISPLAY INVISIBLE (-6750 4475);
FORCEPROP 2 LAST CDS_LIB mstr_standard
J 0
(-6500 4400);
PAINT ORANGE (-6500 4400);
DISPLAY INVISIBLE (-6500 4400);
FORCEADD OFFPAGE..5
(-7100 2000);
FORCEPROP 2 LAST $XR0 252 
J 0
(-7355 2000);
DISPLAY 0.638298 (-7355 2000);
PAINT MONO (-7355 2000);
FORCEPROP 1 LAST COMMENT_BODY TRUE
J 0
(-7000 1925);
DISPLAY 0.872340 (-7000 1925);
PAINT GREEN (-7000 1925);
DISPLAY INVISIBLE (-7000 1925);
FORCEPROP 1 LAST OFFPAGE TRUE
J 0
(-6775 1875);
DISPLAY 0.872340 (-6775 1875);
PAINT GREEN (-6775 1875);
DISPLAY INVISIBLE (-6775 1875);
FORCEPROP 2 LAST CDS_LIB mstr_standard
J 0
(-7100 2000);
PAINT MONO (-7100 2000);
DISPLAY INVISIBLE (-7100 2000);
FORCEPROP 2 LAST PATH I146
J 0
(-7050 2075);
DISPLAY 1.021277 (-7050 2075);
PAINT ORANGE (-7050 2075);
DISPLAY INVISIBLE (-7050 2075);
FORCEADD OFFPAGE..5
(-7100 2050);
FORCEPROP 2 LAST $XR0 252 
J 0
(-7355 2050);
DISPLAY 0.638298 (-7355 2050);
PAINT MONO (-7355 2050);
FORCEPROP 1 LAST COMMENT_BODY TRUE
J 0
(-7000 1975);
DISPLAY 0.872340 (-7000 1975);
PAINT GREEN (-7000 1975);
DISPLAY INVISIBLE (-7000 1975);
FORCEPROP 1 LAST OFFPAGE TRUE
J 0
(-6775 1925);
DISPLAY 0.872340 (-6775 1925);
PAINT GREEN (-6775 1925);
DISPLAY INVISIBLE (-6775 1925);
FORCEPROP 2 LAST CDS_LIB mstr_standard
J 0
(-7100 2050);
PAINT MONO (-7100 2050);
DISPLAY INVISIBLE (-7100 2050);
FORCEPROP 2 LAST PATH I147
J 0
(-7050 2125);
DISPLAY 1.021277 (-7050 2125);
PAINT ORANGE (-7050 2125);
DISPLAY INVISIBLE (-7050 2125);
FORCEADD OFFPAGE..5
(-7100 2200);
FORCEPROP 2 LAST $XR0 146 
J 0
(-7475 2200);
DISPLAY 0.638298 (-7475 2200);
PAINT MONO (-7475 2200);
FORCEPROP 2 LAST $XR1 252 
J 0
(-7595 2200);
DISPLAY 0.638298 (-7595 2200);
PAINT MONO (-7595 2200);
FORCEPROP 1 LAST COMMENT_BODY TRUE
J 0
(-7000 2125);
DISPLAY 0.872340 (-7000 2125);
PAINT GREEN (-7000 2125);
DISPLAY INVISIBLE (-7000 2125);
FORCEPROP 1 LAST OFFPAGE TRUE
J 0
(-6775 2075);
DISPLAY 0.872340 (-6775 2075);
PAINT GREEN (-6775 2075);
DISPLAY INVISIBLE (-6775 2075);
FORCEPROP 2 LAST PATH I149
J 0
(-7050 2275);
DISPLAY 1.021277 (-7050 2275);
PAINT ORANGE (-7050 2275);
DISPLAY INVISIBLE (-7050 2275);
FORCEPROP 2 LAST CDS_LIB mstr_standard
J 0
(-7100 2200);
PAINT MONO (-7100 2200);
DISPLAY INVISIBLE (-7100 2200);
FORCEADD OFFPAGE..3
R 2
(-7100 2250);
FORCEPROP 2 LAST $XR0 252 
J 0
(-7380 2250);
DISPLAY 0.638298 (-7380 2250);
PAINT MONO (-7380 2250);
FORCEPROP 2 LAST $XR1 146 
J 0
(-7380 2214);
DISPLAY 0.638298 (-7380 2214);
PAINT MONO (-7380 2214);
FORCEPROP 1 LAST COMMENT_BODY TRUE
J 2
(-7050 2150);
DISPLAY 1.170213 (-7050 2150);
PAINT GREEN (-7050 2150);
DISPLAY INVISIBLE (-7050 2150);
FORCEPROP 1 LAST OFFPAGE TRUE
J 2
(-7425 2125);
PAINT GREEN (-7425 2125);
DISPLAY INVISIBLE (-7425 2125);
FORCEPROP 2 LAST BOM_COST SM_CONTROLLER
J 2
(-7575 2300);
PAINT MONO (-7575 2300);
DISPLAY INVISIBLE (-7575 2300);
FORCEPROP 2 LAST ROOM BMC
J 2
(-7575 2300);
PAINT MONO (-7575 2300);
DISPLAY INVISIBLE (-7575 2300);
FORCEPROP 2 LAST PATH I150
J 0
(-7050 2325);
DISPLAY 1.021277 (-7050 2325);
PAINT ORANGE (-7050 2325);
DISPLAY INVISIBLE (-7050 2325);
FORCEPROP 2 LAST CDS_LIB mstr_standard
J 0
(-7100 2250);
PAINT MONO (-7100 2250);
DISPLAY INVISIBLE (-7100 2250);
FORCEADD RES..2
R 1
(-7300 400);
FORCEPROP 1 LAST WATTAGE 1/16W
J 0
(-7200 365);
DISPLAY 0.617021 (-7200 365);
PAINT SKYBLUE (-7200 365);
FORCEPROP 1 LAST TOLERANCE 1%
J 0
(-7100 445);
DISPLAY 0.617021 (-7100 445);
PAINT SKYBLUE (-7100 445);
FORCEPROP 1 LAST MATERIAL CHIP
J 0
(-7050 365);
DISPLAY 0.617021 (-7050 365);
PAINT SKYBLUE (-7050 365);
FORCEPROP 1 LASTPIN (-7200 400) $PN 2
J 0
(-7210 405);
DISPLAY 0.617021 (-7210 405);
PAINT ORANGE (-7210 405);
FORCEPROP 1 LASTPIN (-7400 400) $PN 1
J 0
(-7412 405);
DISPLAY 0.617021 (-7412 405);
PAINT ORANGE (-7412 405);
FORCEPROP 1 LAST LOCATION R25W129
J 0
(-7450 445);
DISPLAY 0.617021 (-7450 445);
PAINT AQUA (-7450 445);
FORCEPROP 1 LAST PACK_TYPE 0402
J 0
(-6675 365);
DISPLAY 0.617021 (-6675 365);
PAINT SKYBLUE (-6675 365);
FORCEPROP 1 LAST PART_NUMBER G21796-072
J 0
(-6925 365);
DISPLAY 0.617021 (-6925 365);
PAINT BLUE (-6925 365);
FORCEPROP 1 LAST VALUE 4.75K
J 0
(-7250 445);
DISPLAY 0.617021 (-7250 445);
PAINT SKYBLUE (-7250 445);
FORCEPROP 2 LAST CDS_LOCATION R25W129
R 1
J 0
(-7425 445);
DISPLAY 0.617021 (-7425 445);
PAINT AQUA (-7425 445);
DISPLAY INVISIBLE (-7425 445);
FORCEPROP 0 LAST CDS_SEC 1
R 1
J 0
(-7475 450);
PAINT MONO (-7475 450);
DISPLAY INVISIBLE (-7475 450);
FORCEPROP 2 LAST CDS_LIB mstr_discrete
R 1
J 0
(-7300 400);
PAINT ORANGE (-7300 400);
DISPLAY INVISIBLE (-7300 400);
FORCEPROP 0 LAST ROOM CPU_FANS
R 1
J 0
(-7525 450);
DISPLAY 1.021277 (-7525 450);
PAINT ORANGE (-7525 450);
DISPLAY INVISIBLE (-7525 450);
FORCEPROP 2 LAST SEC 1
R 1
J 0
(-7525 450);
DISPLAY 0.680851 (-7525 450);
PAINT MONO (-7525 450);
DISPLAY INVISIBLE (-7525 450);
FORCEPROP 2 LAST SEC_TYPE 0402
R 1
J 0
(-7525 450);
DISPLAY 1.021277 (-7525 450);
PAINT ORANGE (-7525 450);
DISPLAY INVISIBLE (-7525 450);
FORCEPROP 0 LAST BOM_COST SM_THERM
R 1
J 0
(-7625 450);
DISPLAY 1.021277 (-7625 450);
PAINT ORANGE (-7625 450);
DISPLAY INVISIBLE (-7625 450);
FORCEPROP 1 LAST PATH I152
R 1
J 0
(-7475 450);
DISPLAY 0.978723 (-7475 450);
PAINT WHITE (-7475 450);
DISPLAY INVISIBLE (-7475 450);
FORCEADD RES..2
R 1
(-7300 250);
FORCEPROP 1 LAST PACK_TYPE 0402
J 0
(-6675 215);
DISPLAY 0.617021 (-6675 215);
PAINT SKYBLUE (-6675 215);
FORCEPROP 1 LAST LOCATION R25W130
J 0
(-7450 295);
DISPLAY 0.617021 (-7450 295);
PAINT AQUA (-7450 295);
FORCEPROP 1 LASTPIN (-7400 250) $PN 1
J 0
(-7412 255);
DISPLAY 0.617021 (-7412 255);
PAINT ORANGE (-7412 255);
FORCEPROP 1 LASTPIN (-7200 250) $PN 2
J 0
(-7210 255);
DISPLAY 0.617021 (-7210 255);
PAINT ORANGE (-7210 255);
FORCEPROP 1 LAST VALUE 4.75K
J 0
(-7250 295);
DISPLAY 0.617021 (-7250 295);
PAINT SKYBLUE (-7250 295);
FORCEPROP 1 LAST WATTAGE 1/16W
J 0
(-7200 215);
DISPLAY 0.617021 (-7200 215);
PAINT SKYBLUE (-7200 215);
FORCEPROP 1 LAST MATERIAL CHIP
J 0
(-7050 215);
DISPLAY 0.617021 (-7050 215);
PAINT SKYBLUE (-7050 215);
FORCEPROP 1 LAST PART_NUMBER G21796-072
J 0
(-6925 215);
DISPLAY 0.617021 (-6925 215);
PAINT BLUE (-6925 215);
FORCEPROP 1 LAST TOLERANCE 1%
J 0
(-7100 295);
DISPLAY 0.617021 (-7100 295);
PAINT SKYBLUE (-7100 295);
FORCEPROP 2 LAST CDS_LOCATION R25W130
R 1
J 0
(-7425 295);
DISPLAY 0.617021 (-7425 295);
PAINT AQUA (-7425 295);
DISPLAY INVISIBLE (-7425 295);
FORCEPROP 0 LAST BOM_COST SM_THERM
R 1
J 0
(-7625 300);
DISPLAY 1.021277 (-7625 300);
PAINT ORANGE (-7625 300);
DISPLAY INVISIBLE (-7625 300);
FORCEPROP 2 LAST SEC_TYPE 0402
R 1
J 0
(-7525 300);
DISPLAY 1.021277 (-7525 300);
PAINT ORANGE (-7525 300);
DISPLAY INVISIBLE (-7525 300);
FORCEPROP 2 LAST SEC 1
R 1
J 0
(-7525 300);
DISPLAY 0.680851 (-7525 300);
PAINT MONO (-7525 300);
DISPLAY INVISIBLE (-7525 300);
FORCEPROP 0 LAST ROOM CPU_FANS
R 1
J 0
(-7525 300);
DISPLAY 1.021277 (-7525 300);
PAINT ORANGE (-7525 300);
DISPLAY INVISIBLE (-7525 300);
FORCEPROP 2 LAST CDS_LIB mstr_discrete
R 1
J 0
(-7300 250);
PAINT ORANGE (-7300 250);
DISPLAY INVISIBLE (-7300 250);
FORCEPROP 0 LAST CDS_SEC 1
R 1
J 0
(-7475 300);
PAINT MONO (-7475 300);
DISPLAY INVISIBLE (-7475 300);
FORCEPROP 1 LAST PATH I153
R 1
J 0
(-7475 300);
DISPLAY 0.978723 (-7475 300);
PAINT WHITE (-7475 300);
DISPLAY INVISIBLE (-7475 300);
FORCEADD P3V3..1
(-7550 500);
FORCEPROP 3 LASTPIN (-7550 450) SIG_NAME P3V3\g
J 0
(-7540 460);
DISPLAY 0.659574 (-7540 460);
PAINT MONO (-7540 460);
DISPLAY INVISIBLE (-7540 460);
FORCEPROP 1 LAST HDL_POWER P3V3
J 0
(-7875 375);
DISPLAY 0.872340 (-7875 375);
PAINT ORANGE (-7875 375);
DISPLAY INVISIBLE (-7875 375);
FORCEPROP 1 LAST BODY_TYPE PLUMBING
J 0
(-7595 457);
DISPLAY 0.340426 (-7595 457);
PAINT GREEN (-7595 457);
DISPLAY INVISIBLE (-7595 457);
FORCEPROP 1 LAST PATH I154
J 0
(-7505 502);
DISPLAY 0.340426 (-7505 502);
PAINT GREEN (-7505 502);
DISPLAY INVISIBLE (-7505 502);
FORCEPROP 2 LAST CDS_LIB mstr_symbols
J 0
(-7550 500);
PAINT ORANGE (-7550 500);
DISPLAY INVISIBLE (-7550 500);
FORCEPROP 1 LAST SIZE 1B
J 0
(-7505 522);
DISPLAY 0.340426 (-7505 522);
PAINT GREEN (-7505 522);
DISPLAY INVISIBLE (-7505 522);
FORCEPROP 1 LAST VOLTAGE 3.3V
J 0
(-7595 457);
DISPLAY 0.340426 (-7595 457);
PAINT SKYBLUE (-7595 457);
DISPLAY INVISIBLE (-7595 457);
FORCEADD OFFPAGE..3
(-1450 4500);
FORCEPROP 2 LAST $XR0 115 
J 0
(-1236 4500);
DISPLAY 0.638298 (-1236 4500);
PAINT MONO (-1236 4500);
FORCEPROP 1 LAST COMMENT_BODY TRUE
J 0
(-1500 4400);
DISPLAY 0.872340 (-1500 4400);
PAINT GREEN (-1500 4400);
DISPLAY INVISIBLE (-1500 4400);
FORCEPROP 1 LAST OFFPAGE TRUE
J 0
(-1125 4375);
DISPLAY 0.872340 (-1125 4375);
PAINT GREEN (-1125 4375);
DISPLAY INVISIBLE (-1125 4375);
FORCEPROP 2 LAST PATH I155
J 0
(-1225 4550);
DISPLAY 1.021277 (-1225 4550);
PAINT ORANGE (-1225 4550);
DISPLAY INVISIBLE (-1225 4550);
FORCEPROP 2 LAST CDS_LIB mstr_standard
J 0
(-1450 4500);
PAINT ORANGE (-1450 4500);
DISPLAY INVISIBLE (-1450 4500);
FORCEADD OFFPAGE..3
(-1450 4450);
FORCEPROP 2 LAST $XR0 115 
J 0
(-1236 4450);
DISPLAY 0.638298 (-1236 4450);
PAINT MONO (-1236 4450);
FORCEPROP 1 LAST COMMENT_BODY TRUE
J 0
(-1500 4350);
DISPLAY 0.872340 (-1500 4350);
PAINT GREEN (-1500 4350);
DISPLAY INVISIBLE (-1500 4350);
FORCEPROP 1 LAST OFFPAGE TRUE
J 0
(-1125 4325);
DISPLAY 0.872340 (-1125 4325);
PAINT GREEN (-1125 4325);
DISPLAY INVISIBLE (-1125 4325);
FORCEPROP 2 LAST PATH I156
J 0
(-1225 4500);
DISPLAY 1.021277 (-1225 4500);
PAINT ORANGE (-1225 4500);
DISPLAY INVISIBLE (-1225 4500);
FORCEPROP 2 LAST CDS_LIB mstr_standard
J 0
(-1450 4450);
PAINT ORANGE (-1450 4450);
DISPLAY INVISIBLE (-1450 4450);
FORCEADD OFFPAGE..3
(-1450 4300);
FORCEPROP 2 LAST $XR0 115 
J 0
(-1236 4300);
DISPLAY 0.638298 (-1236 4300);
PAINT MONO (-1236 4300);
FORCEPROP 1 LAST COMMENT_BODY TRUE
J 0
(-1500 4200);
DISPLAY 0.872340 (-1500 4200);
PAINT GREEN (-1500 4200);
DISPLAY INVISIBLE (-1500 4200);
FORCEPROP 1 LAST OFFPAGE TRUE
J 0
(-1125 4175);
DISPLAY 0.872340 (-1125 4175);
PAINT GREEN (-1125 4175);
DISPLAY INVISIBLE (-1125 4175);
FORCEPROP 2 LAST PATH I157
J 0
(-1225 4350);
DISPLAY 1.021277 (-1225 4350);
PAINT ORANGE (-1225 4350);
DISPLAY INVISIBLE (-1225 4350);
FORCEPROP 2 LAST CDS_LIB mstr_standard
J 0
(-1450 4300);
PAINT ORANGE (-1450 4300);
DISPLAY INVISIBLE (-1450 4300);
FORCEADD OFFPAGE..3
(-1450 4350);
FORCEPROP 2 LAST $XR0 115 
J 0
(-1236 4350);
DISPLAY 0.638298 (-1236 4350);
PAINT MONO (-1236 4350);
FORCEPROP 1 LAST COMMENT_BODY TRUE
J 0
(-1500 4250);
DISPLAY 0.872340 (-1500 4250);
PAINT GREEN (-1500 4250);
DISPLAY INVISIBLE (-1500 4250);
FORCEPROP 1 LAST OFFPAGE TRUE
J 0
(-1125 4225);
DISPLAY 0.872340 (-1125 4225);
PAINT GREEN (-1125 4225);
DISPLAY INVISIBLE (-1125 4225);
FORCEPROP 2 LAST PATH I158
J 0
(-1225 4400);
DISPLAY 1.021277 (-1225 4400);
PAINT ORANGE (-1225 4400);
DISPLAY INVISIBLE (-1225 4400);
FORCEPROP 2 LAST CDS_LIB mstr_standard
J 0
(-1450 4350);
PAINT ORANGE (-1450 4350);
DISPLAY INVISIBLE (-1450 4350);
FORCEADD CAP..1
R 1
(-550 4350);
FORCEPROP 1 LASTPIN (-650 4350) $PN 1
J 0
(-655 4360);
DISPLAY 0.617021 (-655 4360);
PAINT ORANGE (-655 4360);
FORCEPROP 1 LAST TOLERANCE 10%
J 0
(-800 4425);
DISPLAY 0.617021 (-800 4425);
PAINT SKYBLUE (-800 4425);
FORCEPROP 1 LASTPIN (-450 4350) $PN 2
J 0
(-455 4360);
DISPLAY 0.617021 (-455 4360);
PAINT ORANGE (-455 4360);
FORCEPROP 1 LAST MATERIAL X7R
J 0
(-650 4425);
DISPLAY 0.617021 (-650 4425);
PAINT SKYBLUE (-650 4425);
FORCEPROP 1 LAST LOCATION C1W21
J 0
(-800 4475);
DISPLAY 0.617021 (-800 4475);
PAINT AQUA (-800 4475);
FORCEPROP 1 LAST VALUE 0.033UF
J 0
(-650 4475);
DISPLAY 0.617021 (-650 4475);
PAINT SKYBLUE (-650 4475);
FORCEPROP 1 LAST PART_NUMBER 603269-064
J 0
(-500 4425);
DISPLAY 0.617021 (-500 4425);
PAINT BLUE (-500 4425);
FORCEPROP 1 LAST PACK_TYPE 0603LF
J 0
(-300 4475);
DISPLAY 0.617021 (-300 4475);
PAINT SKYBLUE (-300 4475);
FORCEPROP 1 LAST VOLTAGE 50V
J 0
(-450 4475);
DISPLAY 0.617021 (-450 4475);
PAINT SKYBLUE (-450 4475);
FORCEPROP 2 LAST CDS_LIB mstr_discrete
R 1
J 0
(-550 4350);
PAINT ORANGE (-550 4350);
DISPLAY INVISIBLE (-550 4350);
FORCEPROP 0 LAST ROOM HOT_SWAP
R 1
J 0
(-750 4400);
DISPLAY 1.021277 (-750 4400);
PAINT ORANGE (-750 4400);
DISPLAY INVISIBLE (-750 4400);
FORCEPROP 2 LAST SEC 1
R 1
J 0
(-750 4400);
DISPLAY 0.680851 (-750 4400);
PAINT MONO (-750 4400);
DISPLAY INVISIBLE (-750 4400);
FORCEPROP 2 LAST SEC_TYPE 0603LF
R 1
J 0
(-750 4400);
DISPLAY 1.021277 (-750 4400);
PAINT ORANGE (-750 4400);
DISPLAY INVISIBLE (-750 4400);
FORCEPROP 1 LAST PATH I160
R 1
J 0
(-700 4400);
DISPLAY 0.978723 (-700 4400);
PAINT WHITE (-700 4400);
DISPLAY INVISIBLE (-700 4400);
FORCEPROP 2 LAST CDS_LOCATION C1W21
R 1
J 0
(-650 4400);
DISPLAY 0.617021 (-650 4400);
PAINT AQUA (-650 4400);
DISPLAY INVISIBLE (-650 4400);
FORCEADD OFFPAGE..5
R 2
(-1475 1950);
FORCEPROP 2 LAST $XR0 254 
J 0
(-1286 1950);
DISPLAY 0.638298 (-1286 1950);
PAINT MONO (-1286 1950);
FORCEPROP 2 LAST PATH I161
J 0
(-1025 2000);
DISPLAY 1.021277 (-1025 2000);
PAINT ORANGE (-1025 2000);
DISPLAY INVISIBLE (-1025 2000);
FORCEPROP 1 LAST COMMENT_BODY TRUE
J 2
(-1575 1875);
DISPLAY 0.872340 (-1575 1875);
PAINT GREEN (-1575 1875);
DISPLAY INVISIBLE (-1575 1875);
FORCEPROP 1 LAST OFFPAGE TRUE
J 2
(-1800 1825);
DISPLAY 0.872340 (-1800 1825);
PAINT GREEN (-1800 1825);
DISPLAY INVISIBLE (-1800 1825);
FORCEPROP 2 LAST CDS_LIB mstr_standard
J 2
(-1475 1950);
PAINT MONO (-1475 1950);
DISPLAY INVISIBLE (-1475 1950);
FORCEADD OFFPAGE..1
R 2
(-1475 1900);
FORCEPROP 2 LAST $XR0 255 
J 0
(-1289 1900);
DISPLAY 0.638298 (-1289 1900);
PAINT MONO (-1289 1900);
FORCEPROP 1 LAST COMMENT_BODY TRUE
J 2
(-1600 1800);
DISPLAY 0.872340 (-1600 1800);
PAINT GREEN (-1600 1800);
DISPLAY INVISIBLE (-1600 1800);
FORCEPROP 1 LAST OFFPAGE TRUE
J 2
(-1800 1775);
DISPLAY 0.872340 (-1800 1775);
PAINT GREEN (-1800 1775);
DISPLAY INVISIBLE (-1800 1775);
FORCEPROP 2 LAST CDS_LIB mstr_standard
J 2
(-1475 1900);
PAINT MONO (-1475 1900);
DISPLAY INVISIBLE (-1475 1900);
FORCEPROP 2 LAST PATH I163
J 0
(-1025 1950);
DISPLAY 1.021277 (-1025 1950);
PAINT ORANGE (-1025 1950);
DISPLAY INVISIBLE (-1025 1950);
FORCEADD OFFPAGE..1
R 2
(-1475 1850);
FORCEPROP 2 LAST $XR0 111 
J 0
(-1289 1850);
DISPLAY 0.638298 (-1289 1850);
PAINT MONO (-1289 1850);
FORCEPROP 2 LAST $XR1 255 
J 0
(-1169 1850);
DISPLAY 0.638298 (-1169 1850);
PAINT MONO (-1169 1850);
FORCEPROP 1 LAST COMMENT_BODY TRUE
J 2
(-1600 1750);
DISPLAY 0.872340 (-1600 1750);
PAINT GREEN (-1600 1750);
DISPLAY INVISIBLE (-1600 1750);
FORCEPROP 1 LAST OFFPAGE TRUE
J 2
(-1800 1725);
DISPLAY 0.872340 (-1800 1725);
PAINT GREEN (-1800 1725);
DISPLAY INVISIBLE (-1800 1725);
FORCEPROP 2 LAST PATH I165
J 0
(-1025 1900);
DISPLAY 1.021277 (-1025 1900);
PAINT ORANGE (-1025 1900);
DISPLAY INVISIBLE (-1025 1900);
FORCEPROP 2 LAST CDS_LIB mstr_standard
J 2
(-1475 1850);
PAINT MONO (-1475 1850);
DISPLAY INVISIBLE (-1475 1850);
FORCEADD RES..1
(-1600 1800);
FORCEPROP 1 LASTPIN (-1500 1800) $PN 2
J 0
(-1538 1812);
DISPLAY 0.617021 (-1538 1812);
PAINT ORANGE (-1538 1812);
FORCEPROP 1 LAST TOLERANCE 5%
J 0
(-1450 1750);
DISPLAY 0.617021 (-1450 1750);
PAINT SKYBLUE (-1450 1750);
FORCEPROP 1 LAST WATTAGE 1/16W
J 0
(-1350 1750);
DISPLAY 0.617021 (-1350 1750);
PAINT SKYBLUE (-1350 1750);
FORCEPROP 1 LAST PART_NUMBER G21497-005
J 0
(-1600 1700);
DISPLAY 0.617021 (-1600 1700);
PAINT BLUE (-1600 1700);
FORCEPROP 1 LAST PACK_TYPE 0402
J 0
(-1350 1700);
DISPLAY 0.617021 (-1350 1700);
PAINT SKYBLUE (-1350 1700);
FORCEPROP 1 LAST VALUE 0.0
J 0
(-1550 1750);
DISPLAY 0.617021 (-1550 1750);
PAINT SKYBLUE (-1550 1750);
FORCEPROP 1 LASTPIN (-1700 1800) $PN 1
J 0
(-1688 1812);
DISPLAY 0.617021 (-1688 1812);
PAINT ORANGE (-1688 1812);
FORCEPROP 1 LAST LOCATION R25W184
J 0
(-1750 1750);
DISPLAY 0.617021 (-1750 1750);
PAINT AQUA (-1750 1750);
FORCEPROP 1 LAST MATERIAL CHIP
J 0
(-1750 1700);
DISPLAY 0.617021 (-1750 1700);
PAINT SKYBLUE (-1750 1700);
FORCEPROP 0 LAST ROOM BMC
J 0
(-1650 1950);
DISPLAY 1.021277 (-1650 1950);
PAINT ORANGE (-1650 1950);
DISPLAY INVISIBLE (-1650 1950);
FORCEPROP 2 LAST BOM_COST SM_CONTROLLER
J 0
(-1538 1852);
DISPLAY 0.787234 (-1538 1852);
PAINT SKYBLUE (-1538 1852);
DISPLAY INVISIBLE (-1538 1852);
FORCEPROP 2 LAST SEC_TYPE 0402
J 0
(-1650 2000);
DISPLAY 1.021277 (-1650 2000);
PAINT ORANGE (-1650 2000);
DISPLAY INVISIBLE (-1650 2000);
FORCEPROP 2 LAST SEC 1
J 0
(-1650 2000);
DISPLAY 0.680851 (-1650 2000);
PAINT MONO (-1650 2000);
DISPLAY INVISIBLE (-1650 2000);
FORCEPROP 0 LAST CDS_SEC 1
J 0
(-1650 1900);
PAINT MONO (-1650 1900);
DISPLAY INVISIBLE (-1650 1900);
FORCEPROP 2 LAST CDS_LIB mstr_discrete
J 0
(-1600 1800);
PAINT ORANGE (-1600 1800);
DISPLAY INVISIBLE (-1600 1800);
FORCEPROP 1 LAST PATH I166
J 0
(-1650 1950);
DISPLAY 0.978723 (-1650 1950);
PAINT WHITE (-1650 1950);
DISPLAY INVISIBLE (-1650 1950);
FORCEPROP 2 LAST CDS_LOCATION R25W184
J 0
(-1650 1850);
DISPLAY 0.617021 (-1650 1850);
PAINT AQUA (-1650 1850);
DISPLAY INVISIBLE (-1650 1850);
FORCEADD OFFPAGE..5
R 2
(-500 1800);
FORCEPROP 2 LAST $XR0 191 
J 0
(-311 1800);
DISPLAY 0.638298 (-311 1800);
PAINT MONO (-311 1800);
FORCEPROP 2 LAST $XR1 134 
J 0
(-191 1800);
DISPLAY 0.638298 (-191 1800);
PAINT MONO (-191 1800);
FORCEPROP 2 LAST $XR2 145 
J 0
(-311 1764);
DISPLAY 0.638298 (-311 1764);
PAINT MONO (-311 1764);
FORCEPROP 2 LAST $XR3 146 
J 0
(-191 1764);
DISPLAY 0.638298 (-191 1764);
PAINT MONO (-191 1764);
FORCEPROP 2 LAST $XR4 184 
J 0
(-311 1836);
DISPLAY 0.638298 (-311 1836);
PAINT MONO (-311 1836);
FORCEPROP 2 LAST PATH I167
J 0
(-300 1850);
DISPLAY 1.021277 (-300 1850);
PAINT ORANGE (-300 1850);
DISPLAY INVISIBLE (-300 1850);
FORCEPROP 2 LAST CDS_LIB mstr_standard
J 2
(-500 1800);
PAINT MONO (-500 1800);
DISPLAY INVISIBLE (-500 1800);
FORCEPROP 1 LAST OFFPAGE TRUE
J 2
(-825 1675);
DISPLAY 0.872340 (-825 1675);
PAINT GREEN (-825 1675);
DISPLAY INVISIBLE (-825 1675);
FORCEPROP 1 LAST COMMENT_BODY TRUE
J 2
(-600 1725);
DISPLAY 0.872340 (-600 1725);
PAINT GREEN (-600 1725);
DISPLAY INVISIBLE (-600 1725);
FORCEADD OFFPAGE..5
(-6900 1150);
FORCEPROP 2 LAST $XR0 249 
J 0
(-7155 1150);
DISPLAY 0.638298 (-7155 1150);
PAINT MONO (-7155 1150);
FORCEPROP 2 LAST CDS_LIB mstr_standard
J 0
(-6900 1150);
PAINT MONO (-6900 1150);
DISPLAY INVISIBLE (-6900 1150);
FORCEPROP 1 LAST OFFPAGE TRUE
J 0
(-6575 1025);
DISPLAY 0.872340 (-6575 1025);
PAINT GREEN (-6575 1025);
DISPLAY INVISIBLE (-6575 1025);
FORCEPROP 1 LAST COMMENT_BODY TRUE
J 0
(-6800 1075);
DISPLAY 0.872340 (-6800 1075);
PAINT GREEN (-6800 1075);
DISPLAY INVISIBLE (-6800 1075);
FORCEPROP 2 LAST PATH I168
J 0
(-7150 1200);
DISPLAY 1.021277 (-7150 1200);
PAINT ORANGE (-7150 1200);
DISPLAY INVISIBLE (-7150 1200);
FORCEADD OFFPAGE..5
(-6500 4500);
FORCEPROP 2 LAST $XR0 166 
J 0
(-6755 4500);
DISPLAY 0.638298 (-6755 4500);
PAINT MONO (-6755 4500);
FORCEPROP 2 LAST PATH I169
J 0
(-6800 4550);
DISPLAY 1.021277 (-6800 4550);
PAINT ORANGE (-6800 4550);
DISPLAY INVISIBLE (-6800 4550);
FORCEPROP 1 LAST COMMENT_BODY TRUE
J 0
(-6400 4425);
DISPLAY 0.872340 (-6400 4425);
PAINT GREEN (-6400 4425);
DISPLAY INVISIBLE (-6400 4425);
FORCEPROP 1 LAST OFFPAGE TRUE
J 0
(-6175 4375);
DISPLAY 0.872340 (-6175 4375);
PAINT GREEN (-6175 4375);
DISPLAY INVISIBLE (-6175 4375);
FORCEPROP 2 LAST CDS_LIB mstr_standard
J 0
(-6500 4500);
PAINT MONO (-6500 4500);
DISPLAY INVISIBLE (-6500 4500);
FORCEADD OFFPAGE..5
(-6500 4000);
FORCEPROP 2 LAST $XR0 120 
J 0
(-6755 4000);
DISPLAY 0.638298 (-6755 4000);
PAINT MONO (-6755 4000);
FORCEPROP 2 LAST $XR1 133 
J 0
(-6875 4000);
DISPLAY 0.638298 (-6875 4000);
PAINT MONO (-6875 4000);
FORCEPROP 2 LAST $XR2 119 
J 0
(-6995 4000);
DISPLAY 0.638298 (-6995 4000);
PAINT MONO (-6995 4000);
FORCEPROP 1 LAST COMMENT_BODY TRUE
J 0
(-6400 3925);
DISPLAY 0.872340 (-6400 3925);
PAINT GREEN (-6400 3925);
DISPLAY INVISIBLE (-6400 3925);
FORCEPROP 1 LAST OFFPAGE TRUE
J 0
(-6175 3875);
DISPLAY 0.872340 (-6175 3875);
PAINT GREEN (-6175 3875);
DISPLAY INVISIBLE (-6175 3875);
FORCEPROP 2 LAST CDS_LIB mstr_standard
J 0
(-6500 4000);
PAINT MONO (-6500 4000);
DISPLAY INVISIBLE (-6500 4000);
FORCEPROP 2 LAST PATH I21
J 0
(-6450 4075);
DISPLAY 1.021277 (-6450 4075);
PAINT ORANGE (-6450 4075);
DISPLAY INVISIBLE (-6450 4075);
FORCEADD OFFPAGE..1
(-7550 3900);
FORCEPROP 2 LAST $XR0 157 
J 0
(-7802 3900);
DISPLAY 0.638298 (-7802 3900);
PAINT MONO (-7802 3900);
FORCEPROP 2 LAST $XR1 120 
J 0
(-7922 3900);
DISPLAY 0.638298 (-7922 3900);
PAINT MONO (-7922 3900);
FORCEPROP 1 LAST COMMENT_BODY TRUE
J 0
(-7425 3800);
DISPLAY 0.872340 (-7425 3800);
PAINT GREEN (-7425 3800);
DISPLAY INVISIBLE (-7425 3800);
FORCEPROP 1 LAST OFFPAGE TRUE
J 0
(-7225 3775);
DISPLAY 0.872340 (-7225 3775);
PAINT GREEN (-7225 3775);
DISPLAY INVISIBLE (-7225 3775);
FORCEPROP 2 LAST CDS_LIB mstr_standard
J 0
(-7550 3900);
PAINT MONO (-7550 3900);
DISPLAY INVISIBLE (-7550 3900);
FORCEPROP 2 LAST PATH I24
J 0
(-7500 3975);
DISPLAY 1.021277 (-7500 3975);
PAINT ORANGE (-7500 3975);
DISPLAY INVISIBLE (-7500 3975);
FORCEPROP 2 LAST ROOM BMC
J 0
(-7800 3975);
DISPLAY 1.361702 (-7800 3975);
PAINT ORANGE (-7800 3975);
DISPLAY INVISIBLE (-7800 3975);
FORCEPROP 2 LAST BOM_COST SM_CONTROLLER
J 0
(-7100 3950);
PAINT MONO (-7100 3950);
DISPLAY INVISIBLE (-7100 3950);
FORCEADD OFFPAGE..1
(-6500 3500);
FORCEPROP 2 LAST $XR0 119 
J 0
(-6752 3500);
DISPLAY 0.638298 (-6752 3500);
PAINT MONO (-6752 3500);
FORCEPROP 2 LAST $XR1 126 
J 0
(-6872 3500);
DISPLAY 0.638298 (-6872 3500);
PAINT MONO (-6872 3500);
FORCEPROP 1 LAST COMMENT_BODY TRUE
J 0
(-6375 3400);
DISPLAY 0.872340 (-6375 3400);
PAINT GREEN (-6375 3400);
DISPLAY INVISIBLE (-6375 3400);
FORCEPROP 1 LAST OFFPAGE TRUE
J 0
(-6175 3375);
DISPLAY 0.872340 (-6175 3375);
PAINT GREEN (-6175 3375);
DISPLAY INVISIBLE (-6175 3375);
FORCEPROP 2 LAST BOM_COST SM_CONTROLLER
J 0
(-6050 3550);
PAINT MONO (-6050 3550);
DISPLAY INVISIBLE (-6050 3550);
FORCEPROP 2 LAST ROOM BMC
J 0
(-6750 3575);
DISPLAY 1.361702 (-6750 3575);
PAINT ORANGE (-6750 3575);
DISPLAY INVISIBLE (-6750 3575);
FORCEPROP 2 LAST PATH I25
J 0
(-6450 3575);
DISPLAY 1.021277 (-6450 3575);
PAINT ORANGE (-6450 3575);
DISPLAY INVISIBLE (-6450 3575);
FORCEPROP 2 LAST CDS_LIB mstr_standard
J 0
(-6500 3500);
PAINT MONO (-6500 3500);
DISPLAY INVISIBLE (-6500 3500);
FORCEADD RES..1
(-6900 3900);
FORCEPROP 1 LASTPIN (-7000 3900) $PN 1
J 0
(-6988 3912);
DISPLAY 0.638298 (-6988 3912);
PAINT ORANGE (-6988 3912);
FORCEPROP 1 LAST MATERIAL CHIP
J 0
(-7250 3700);
DISPLAY 0.617021 (-7250 3700);
PAINT SKYBLUE (-7250 3700);
FORCEPROP 1 LAST PACK_TYPE 0402
J 0
(-7000 3650);
DISPLAY 0.617021 (-7000 3650);
PAINT SKYBLUE (-7000 3650);
FORCEPROP 1 LAST TOLERANCE 5%
J 0
(-6975 3700);
DISPLAY 0.617021 (-6975 3700);
PAINT SKYBLUE (-6975 3700);
FORCEPROP 1 LAST PART_NUMBER G21497-005
J 0
(-7250 3800);
DISPLAY 0.510638 (-7250 3800);
PAINT BLUE (-7250 3800);
FORCEPROP 1 LAST WATTAGE 1/16W
J 0
(-7275 3750);
DISPLAY 0.638298 (-7275 3750);
PAINT SKYBLUE (-7275 3750);
FORCEPROP 1 LAST VALUE 0.0
J 2
(-6925 3750);
DISPLAY 0.617021 (-6925 3750);
PAINT SKYBLUE (-6925 3750);
FORCEPROP 1 LAST LOCATION R25W83
J 0
(-7000 3800);
DISPLAY 0.617021 (-7000 3800);
PAINT AQUA (-7000 3800);
FORCEPROP 1 LASTPIN (-6800 3900) $PN 2
J 0
(-6838 3912);
DISPLAY 0.638298 (-6838 3912);
PAINT ORANGE (-6838 3912);
FORCEPROP 0 LAST SEC 1
J 0
(-7100 4000);
DISPLAY 0.680851 (-7100 4000);
PAINT MONO (-7100 4000);
DISPLAY INVISIBLE (-7100 4000);
FORCEPROP 2 LAST SEC_TYPE 0402
J 0
(-6950 4100);
DISPLAY 1.021277 (-6950 4100);
PAINT ORANGE (-6950 4100);
DISPLAY INVISIBLE (-6950 4100);
FORCEPROP 1 LAST PATH I26
J 0
(-6950 4050);
DISPLAY 0.978723 (-6950 4050);
PAINT WHITE (-6950 4050);
DISPLAY INVISIBLE (-6950 4050);
FORCEPROP 2 LAST CDS_LIB mstr_discrete
J 0
(-6900 3900);
PAINT MONO (-6900 3900);
DISPLAY INVISIBLE (-6900 3900);
FORCEPROP 0 LAST ROOM USB
J 0
(-6725 4000);
DISPLAY 1.021277 (-6725 4000);
PAINT ORANGE (-6725 4000);
DISPLAY INVISIBLE (-6725 4000);
FORCEPROP 0 LAST BOM_COST MIO_USB
J 0
(-6725 4050);
DISPLAY 1.021277 (-6725 4050);
PAINT ORANGE (-6725 4050);
DISPLAY INVISIBLE (-6725 4050);
FORCEADD OFFPAGE..1
(-6500 3400);
FORCEPROP 2 LAST $XR0 119 
J 0
(-6752 3400);
DISPLAY 0.638298 (-6752 3400);
PAINT MONO (-6752 3400);
FORCEPROP 2 LAST $XR1 133 
J 0
(-6872 3400);
DISPLAY 0.638298 (-6872 3400);
PAINT MONO (-6872 3400);
FORCEPROP 2 LAST $XR2 170 
J 0
(-6992 3400);
DISPLAY 0.638298 (-6992 3400);
PAINT MONO (-6992 3400);
FORCEPROP 2 LAST $XR3 95 
J 0
(-7082 3400);
DISPLAY 0.638298 (-7082 3400);
PAINT MONO (-7082 3400);
FORCEPROP 1 LAST COMMENT_BODY TRUE
J 0
(-6375 3300);
DISPLAY 0.872340 (-6375 3300);
PAINT GREEN (-6375 3300);
DISPLAY INVISIBLE (-6375 3300);
FORCEPROP 1 LAST OFFPAGE TRUE
J 0
(-6175 3275);
DISPLAY 0.872340 (-6175 3275);
PAINT GREEN (-6175 3275);
DISPLAY INVISIBLE (-6175 3275);
FORCEPROP 2 LAST ROOM BMC
J 0
(-6750 3475);
DISPLAY 1.361702 (-6750 3475);
PAINT ORANGE (-6750 3475);
DISPLAY INVISIBLE (-6750 3475);
FORCEPROP 2 LAST BOM_COST SM_CONTROLLER
J 0
(-6050 3450);
PAINT MONO (-6050 3450);
DISPLAY INVISIBLE (-6050 3450);
FORCEPROP 2 LAST PATH I28
J 0
(-6775 3450);
DISPLAY 1.021277 (-6775 3450);
PAINT ORANGE (-6775 3450);
DISPLAY INVISIBLE (-6775 3450);
FORCEPROP 2 LAST CDS_LIB mstr_standard
J 0
(-6500 3400);
PAINT MONO (-6500 3400);
DISPLAY INVISIBLE (-6500 3400);
FORCEADD OFFPAGE..5
(-6500 3450);
FORCEPROP 2 LAST $XR0 120 
J 0
(-6755 3450);
DISPLAY 0.638298 (-6755 3450);
PAINT MONO (-6755 3450);
FORCEPROP 2 LAST $XR1 133 
J 0
(-6875 3450);
DISPLAY 0.638298 (-6875 3450);
PAINT MONO (-6875 3450);
FORCEPROP 2 LAST $XR2 119 
J 0
(-6995 3450);
DISPLAY 0.638298 (-6995 3450);
PAINT MONO (-6995 3450);
FORCEPROP 2 LAST $XR3 182 
J 0
(-7115 3450);
DISPLAY 0.638298 (-7115 3450);
PAINT MONO (-7115 3450);
FORCEPROP 1 LAST COMMENT_BODY TRUE
J 0
(-6400 3375);
DISPLAY 0.872340 (-6400 3375);
PAINT GREEN (-6400 3375);
DISPLAY INVISIBLE (-6400 3375);
FORCEPROP 1 LAST OFFPAGE TRUE
J 0
(-6175 3325);
DISPLAY 0.872340 (-6175 3325);
PAINT GREEN (-6175 3325);
DISPLAY INVISIBLE (-6175 3325);
FORCEPROP 2 LAST PATH I29
J 0
(-6750 3500);
DISPLAY 1.021277 (-6750 3500);
PAINT ORANGE (-6750 3500);
DISPLAY INVISIBLE (-6750 3500);
FORCEPROP 2 LAST ROOM BMC
J 0
(-6750 3525);
DISPLAY 1.361702 (-6750 3525);
PAINT ORANGE (-6750 3525);
DISPLAY INVISIBLE (-6750 3525);
FORCEPROP 2 LAST BOM_COST SM_CONTROLLER
J 0
(-6050 3500);
PAINT MONO (-6050 3500);
DISPLAY INVISIBLE (-6050 3500);
FORCEPROP 2 LAST CDS_LIB mstr_standard
J 2
(-6500 3450);
PAINT ORANGE (-6500 3450);
DISPLAY INVISIBLE (-6500 3450);
FORCEADD RES..2
R 1
(-850 4150);
FORCEPROP 1 LAST PACK_TYPE 0402
J 0
(-950 3790);
DISPLAY 0.617021 (-950 3790);
PAINT SKYBLUE (-950 3790);
FORCEPROP 1 LAST MATERIAL CHIP
J 0
(-950 3890);
DISPLAY 0.617021 (-950 3890);
PAINT SKYBLUE (-950 3890);
FORCEPROP 1 LAST WATTAGE 1/16W
J 0
(-950 3940);
DISPLAY 0.617021 (-950 3940);
PAINT SKYBLUE (-950 3940);
FORCEPROP 1 LAST TOLERANCE 1%
J 0
(-950 3995);
DISPLAY 0.617021 (-950 3995);
PAINT SKYBLUE (-950 3995);
FORCEPROP 1 LAST VALUE 8.2K
J 0
(-950 4045);
DISPLAY 0.617021 (-950 4045);
PAINT SKYBLUE (-950 4045);
FORCEPROP 1 LASTPIN (-950 4150) $PN 1
J 0
(-962 4155);
DISPLAY 0.787234 (-962 4155);
PAINT ORANGE (-962 4155);
FORCEPROP 1 LAST LOCATION R1T25
J 0
(-950 4095);
DISPLAY 0.617021 (-950 4095);
PAINT AQUA (-950 4095);
FORCEPROP 1 LAST PART_NUMBER G21796-345
J 0
(-950 3840);
DISPLAY 0.617021 (-950 3840);
PAINT BLUE (-950 3840);
FORCEPROP 1 LASTPIN (-750 4150) $PN 2
J 0
(-760 4155);
DISPLAY 0.787234 (-760 4155);
PAINT ORANGE (-760 4155);
FORCEPROP 0 LAST ROOM BMC
R 1
J 0
(-1075 4200);
DISPLAY 0.617021 (-1075 4200);
PAINT ORANGE (-1075 4200);
DISPLAY INVISIBLE (-1075 4200);
FORCEPROP 0 LAST BOM_COST SM_CONTROLLER
R 1
J 0
(-1175 4200);
DISPLAY 1.021277 (-1175 4200);
PAINT ORANGE (-1175 4200);
DISPLAY INVISIBLE (-1175 4200);
FORCEPROP 2 LAST CDS_LIB mstr_discrete
J 0
(-850 4150);
PAINT MONO (-850 4150);
DISPLAY INVISIBLE (-850 4150);
FORCEPROP 1 LAST PATH I35
R 1
J 0
(-1025 4200);
DISPLAY 0.978723 (-1025 4200);
PAINT WHITE (-1025 4200);
DISPLAY INVISIBLE (-1025 4200);
FORCEPROP 2 LAST SEC_TYPE 0402
J 0
(-775 4125);
DISPLAY 1.021277 (-775 4125);
PAINT ORANGE (-775 4125);
DISPLAY INVISIBLE (-775 4125);
FORCEPROP 0 LAST SEC 1
R 1
J 0
(-775 4125);
DISPLAY 0.680851 (-775 4125);
PAINT MONO (-775 4125);
DISPLAY INVISIBLE (-775 4125);
FORCEADD GND..1
R 1
(-300 4200);
FORCEPROP 3 LASTPIN (-350 4200) SIG_NAME GND\g
J 0
(-340 4210);
DISPLAY 0.659574 (-340 4210);
PAINT MONO (-340 4210);
DISPLAY INVISIBLE (-340 4210);
FORCEPROP 1 LAST HDL_POWER GND
R 1
J 0
(-450 4200);
DISPLAY 0.872340 (-450 4200);
PAINT GREEN (-450 4200);
DISPLAY INVISIBLE (-450 4200);
FORCEPROP 1 LAST BODY_TYPE PLUMBING
R 1
J 0
(-257 4155);
DISPLAY 0.340426 (-257 4155);
PAINT GREEN (-257 4155);
DISPLAY INVISIBLE (-257 4155);
FORCEPROP 1 LAST VOLTAGE 0.0V
R 1
J 0
(-257 4155);
DISPLAY 0.340426 (-257 4155);
PAINT SKYBLUE (-257 4155);
DISPLAY INVISIBLE (-257 4155);
FORCEPROP 2 LAST CDS_LIB mstr_symbols
R 1
J 0
(-300 4200);
PAINT ORANGE (-300 4200);
DISPLAY INVISIBLE (-300 4200);
FORCEPROP 1 LAST SIZE 1B
R 1
J 0
(-250 4275);
DISPLAY 0.872340 (-250 4275);
PAINT AQUA (-250 4275);
DISPLAY INVISIBLE (-250 4275);
FORCEPROP 1 LAST PATH I36
R 1
J 0
(-300 4275);
DISPLAY 0.872340 (-300 4275);
PAINT AQUA (-300 4275);
DISPLAY INVISIBLE (-300 4275);
FORCEADD RES..2
R 1
(-550 4200);
FORCEPROP 1 LASTPIN (-450 4200) $PN 2
J 0
(-460 4205);
DISPLAY 0.787234 (-460 4205);
PAINT ORANGE (-460 4205);
FORCEPROP 1 LAST TOLERANCE 1%
J 0
(-650 3995);
DISPLAY 0.617021 (-650 3995);
PAINT SKYBLUE (-650 3995);
FORCEPROP 1 LASTPIN (-650 4200) $PN 1
J 0
(-662 4205);
DISPLAY 0.787234 (-662 4205);
PAINT ORANGE (-662 4205);
FORCEPROP 1 LAST PART_NUMBER G21796-345
J 0
(-650 3840);
DISPLAY 0.617021 (-650 3840);
PAINT BLUE (-650 3840);
FORCEPROP 1 LAST PACK_TYPE 0402
J 0
(-650 3790);
DISPLAY 0.617021 (-650 3790);
PAINT SKYBLUE (-650 3790);
FORCEPROP 1 LAST WATTAGE 1/16W
J 0
(-650 3940);
DISPLAY 0.617021 (-650 3940);
PAINT SKYBLUE (-650 3940);
FORCEPROP 1 LAST MATERIAL CHIP
J 0
(-650 3890);
DISPLAY 0.617021 (-650 3890);
PAINT SKYBLUE (-650 3890);
FORCEPROP 1 LAST VALUE 8.2K
J 0
(-650 4045);
DISPLAY 0.617021 (-650 4045);
PAINT SKYBLUE (-650 4045);
FORCEPROP 1 LAST LOCATION R1T26
J 0
(-650 4095);
DISPLAY 0.617021 (-650 4095);
PAINT AQUA (-650 4095);
FORCEPROP 2 LAST SEC 1
R 1
J 0
(-775 4250);
DISPLAY 0.680851 (-775 4250);
PAINT MONO (-775 4250);
DISPLAY INVISIBLE (-775 4250);
FORCEPROP 2 LAST SEC_TYPE 0402
J 0
(-600 4150);
DISPLAY 1.021277 (-600 4150);
PAINT ORANGE (-600 4150);
DISPLAY INVISIBLE (-600 4150);
FORCEPROP 2 LAST CDS_LIB mstr_discrete
R 1
J 0
(-550 4200);
PAINT ORANGE (-550 4200);
DISPLAY INVISIBLE (-550 4200);
FORCEPROP 0 LAST ROOM BMC
R 1
J 0
(-775 4250);
DISPLAY 0.617021 (-775 4250);
PAINT ORANGE (-775 4250);
DISPLAY INVISIBLE (-775 4250);
FORCEPROP 0 LAST BOM_COST SM_CONTROLLER
R 1
J 0
(-875 4250);
DISPLAY 1.021277 (-875 4250);
PAINT ORANGE (-875 4250);
DISPLAY INVISIBLE (-875 4250);
FORCEPROP 1 LAST PATH I37
R 1
J 0
(-725 4250);
DISPLAY 0.978723 (-725 4250);
PAINT WHITE (-725 4250);
DISPLAY INVISIBLE (-725 4250);
FORCEPROP 2 LAST CDS_LOCATION R1T26
R 1
J 0
(-675 4245);
DISPLAY 0.617021 (-675 4245);
PAINT AQUA (-675 4245);
DISPLAY INVISIBLE (-675 4245);
FORCEADD OFFPAGE..2
(-1450 3850);
FORCEPROP 2 LAST $XR0 155 
J 0
(-1261 3850);
DISPLAY 0.638298 (-1261 3850);
PAINT MONO (-1261 3850);
FORCEPROP 1 LAST COMMENT_BODY TRUE
J 0
(-1495 3755);
DISPLAY 0.872340 (-1495 3755);
PAINT GREEN (-1495 3755);
DISPLAY INVISIBLE (-1495 3755);
FORCEPROP 1 LAST OFFPAGE TRUE
J 0
(-1125 3725);
DISPLAY 0.872340 (-1125 3725);
PAINT GREEN (-1125 3725);
DISPLAY INVISIBLE (-1125 3725);
FORCEPROP 2 LAST CDS_LIB mstr_standard
J 0
(-1450 3850);
PAINT ORANGE (-1450 3850);
DISPLAY INVISIBLE (-1450 3850);
FORCEPROP 2 LAST PATH I42
J 0
(-1125 3900);
DISPLAY 1.021277 (-1125 3900);
PAINT ORANGE (-1125 3900);
DISPLAY INVISIBLE (-1125 3900);
FORCEADD OFFPAGE..2
(-1450 3900);
FORCEPROP 2 LAST $XR0 155 
J 0
(-1261 3900);
DISPLAY 0.638298 (-1261 3900);
PAINT MONO (-1261 3900);
FORCEPROP 1 LAST COMMENT_BODY TRUE
J 0
(-1495 3805);
DISPLAY 0.872340 (-1495 3805);
PAINT GREEN (-1495 3805);
DISPLAY INVISIBLE (-1495 3805);
FORCEPROP 1 LAST OFFPAGE TRUE
J 0
(-1125 3775);
DISPLAY 0.872340 (-1125 3775);
PAINT GREEN (-1125 3775);
DISPLAY INVISIBLE (-1125 3775);
FORCEPROP 2 LAST CDS_LIB mstr_standard
J 0
(-1450 3900);
PAINT ORANGE (-1450 3900);
DISPLAY INVISIBLE (-1450 3900);
FORCEPROP 2 LAST PATH I43
J 0
(-1125 3950);
DISPLAY 1.021277 (-1125 3950);
PAINT ORANGE (-1125 3950);
DISPLAY INVISIBLE (-1125 3950);
FORCEADD OFFPAGE..2
(-1450 3950);
FORCEPROP 2 LAST $XR0 155 
J 0
(-1261 3950);
DISPLAY 0.638298 (-1261 3950);
PAINT MONO (-1261 3950);
FORCEPROP 1 LAST COMMENT_BODY TRUE
J 0
(-1495 3855);
DISPLAY 0.872340 (-1495 3855);
PAINT GREEN (-1495 3855);
DISPLAY INVISIBLE (-1495 3855);
FORCEPROP 1 LAST OFFPAGE TRUE
J 0
(-1125 3825);
DISPLAY 0.872340 (-1125 3825);
PAINT GREEN (-1125 3825);
DISPLAY INVISIBLE (-1125 3825);
FORCEPROP 2 LAST CDS_LIB mstr_standard
J 0
(-1450 3950);
PAINT ORANGE (-1450 3950);
DISPLAY INVISIBLE (-1450 3950);
FORCEPROP 2 LAST PATH I44
J 0
(-1125 4000);
DISPLAY 1.021277 (-1125 4000);
PAINT ORANGE (-1125 4000);
DISPLAY INVISIBLE (-1125 4000);
FORCEADD OFFPAGE..2
(-1450 4000);
FORCEPROP 2 LAST $XR0 155 
J 0
(-1261 4000);
DISPLAY 0.638298 (-1261 4000);
PAINT MONO (-1261 4000);
FORCEPROP 1 LAST COMMENT_BODY TRUE
J 0
(-1495 3905);
DISPLAY 0.872340 (-1495 3905);
PAINT GREEN (-1495 3905);
DISPLAY INVISIBLE (-1495 3905);
FORCEPROP 1 LAST OFFPAGE TRUE
J 0
(-1125 3875);
DISPLAY 0.872340 (-1125 3875);
PAINT GREEN (-1125 3875);
DISPLAY INVISIBLE (-1125 3875);
FORCEPROP 2 LAST CDS_LIB mstr_standard
J 0
(-1450 4000);
PAINT ORANGE (-1450 4000);
DISPLAY INVISIBLE (-1450 4000);
FORCEPROP 2 LAST PATH I45
J 0
(-1125 4050);
DISPLAY 1.021277 (-1125 4050);
PAINT ORANGE (-1125 4050);
DISPLAY INVISIBLE (-1125 4050);
FORCEADD OFFPAGE..2
(-1450 3750);
FORCEPROP 2 LAST $XR0 155 
J 0
(-1261 3750);
DISPLAY 0.638298 (-1261 3750);
PAINT MONO (-1261 3750);
FORCEPROP 1 LAST COMMENT_BODY TRUE
J 0
(-1495 3655);
DISPLAY 0.872340 (-1495 3655);
PAINT GREEN (-1495 3655);
DISPLAY INVISIBLE (-1495 3655);
FORCEPROP 1 LAST OFFPAGE TRUE
J 0
(-1125 3625);
DISPLAY 0.872340 (-1125 3625);
PAINT GREEN (-1125 3625);
DISPLAY INVISIBLE (-1125 3625);
FORCEPROP 2 LAST CDS_LIB mstr_standard
J 0
(-1450 3750);
PAINT ORANGE (-1450 3750);
DISPLAY INVISIBLE (-1450 3750);
FORCEPROP 2 LAST PATH I46
J 0
(-1125 3800);
DISPLAY 1.021277 (-1125 3800);
PAINT ORANGE (-1125 3800);
DISPLAY INVISIBLE (-1125 3800);
FORCEADD OFFPAGE..2
(-1450 3700);
FORCEPROP 2 LAST $XR0 155 
J 0
(-1261 3700);
DISPLAY 0.638298 (-1261 3700);
PAINT MONO (-1261 3700);
FORCEPROP 1 LAST COMMENT_BODY TRUE
J 0
(-1495 3605);
DISPLAY 0.872340 (-1495 3605);
PAINT GREEN (-1495 3605);
DISPLAY INVISIBLE (-1495 3605);
FORCEPROP 1 LAST OFFPAGE TRUE
J 0
(-1125 3575);
DISPLAY 0.872340 (-1125 3575);
PAINT GREEN (-1125 3575);
DISPLAY INVISIBLE (-1125 3575);
FORCEPROP 2 LAST CDS_LIB mstr_standard
J 0
(-1450 3700);
PAINT ORANGE (-1450 3700);
DISPLAY INVISIBLE (-1450 3700);
FORCEPROP 2 LAST PATH I47
J 0
(-1125 3750);
DISPLAY 1.021277 (-1125 3750);
PAINT ORANGE (-1125 3750);
DISPLAY INVISIBLE (-1125 3750);
FORCEADD OFFPAGE..2
(-1450 3800);
FORCEPROP 2 LAST $XR0 155 
J 0
(-1261 3800);
DISPLAY 0.638298 (-1261 3800);
PAINT MONO (-1261 3800);
FORCEPROP 1 LAST COMMENT_BODY TRUE
J 0
(-1495 3705);
DISPLAY 0.872340 (-1495 3705);
PAINT GREEN (-1495 3705);
DISPLAY INVISIBLE (-1495 3705);
FORCEPROP 1 LAST OFFPAGE TRUE
J 0
(-1125 3675);
DISPLAY 0.872340 (-1125 3675);
PAINT GREEN (-1125 3675);
DISPLAY INVISIBLE (-1125 3675);
FORCEPROP 2 LAST CDS_LIB mstr_standard
J 0
(-1450 3800);
PAINT ORANGE (-1450 3800);
DISPLAY INVISIBLE (-1450 3800);
FORCEPROP 2 LAST PATH I48
J 0
(-1125 3850);
DISPLAY 1.021277 (-1125 3850);
PAINT ORANGE (-1125 3850);
DISPLAY INVISIBLE (-1125 3850);
FORCEADD OFFPAGE..2
(-1450 4050);
FORCEPROP 2 LAST $XR0 155 
J 0
(-1261 4050);
DISPLAY 0.638298 (-1261 4050);
PAINT MONO (-1261 4050);
FORCEPROP 1 LAST COMMENT_BODY TRUE
J 0
(-1495 3955);
DISPLAY 0.872340 (-1495 3955);
PAINT GREEN (-1495 3955);
DISPLAY INVISIBLE (-1495 3955);
FORCEPROP 1 LAST OFFPAGE TRUE
J 0
(-1125 3925);
DISPLAY 0.872340 (-1125 3925);
PAINT GREEN (-1125 3925);
DISPLAY INVISIBLE (-1125 3925);
FORCEPROP 2 LAST CDS_LIB mstr_standard
J 0
(-1450 4050);
PAINT ORANGE (-1450 4050);
DISPLAY INVISIBLE (-1450 4050);
FORCEPROP 2 LAST PATH I49
J 0
(-1125 4100);
DISPLAY 1.021277 (-1125 4100);
PAINT ORANGE (-1125 4100);
DISPLAY INVISIBLE (-1125 4100);
FORCEADD OFFPAGE..1
(-6500 4650);
FORCEPROP 2 LAST $XR0 119 
J 0
(-6752 4650);
DISPLAY 0.638298 (-6752 4650);
PAINT MONO (-6752 4650);
FORCEPROP 2 LAST $XR1 133 
J 0
(-6872 4650);
DISPLAY 0.638298 (-6872 4650);
PAINT MONO (-6872 4650);
FORCEPROP 1 LAST COMMENT_BODY TRUE
J 0
(-6375 4550);
DISPLAY 0.872340 (-6375 4550);
PAINT GREEN (-6375 4550);
DISPLAY INVISIBLE (-6375 4550);
FORCEPROP 1 LAST OFFPAGE TRUE
J 0
(-6175 4525);
DISPLAY 0.872340 (-6175 4525);
PAINT GREEN (-6175 4525);
DISPLAY INVISIBLE (-6175 4525);
FORCEPROP 2 LAST ROOM BMC
J 0
(-6750 4725);
DISPLAY 1.361702 (-6750 4725);
PAINT ORANGE (-6750 4725);
DISPLAY INVISIBLE (-6750 4725);
FORCEPROP 2 LAST BOM_COST SM_CONTROLLER
J 0
(-6050 4700);
PAINT MONO (-6050 4700);
DISPLAY INVISIBLE (-6050 4700);
FORCEPROP 2 LAST PATH I5
J 0
(-6450 4725);
DISPLAY 1.021277 (-6450 4725);
PAINT ORANGE (-6450 4725);
DISPLAY INVISIBLE (-6450 4725);
FORCEPROP 2 LAST CDS_LIB mstr_standard
J 0
(-6500 4650);
PAINT MONO (-6500 4650);
DISPLAY INVISIBLE (-6500 4650);
FORCEADD OFFPAGE..2
(-1250 2650);
FORCEPROP 2 LAST $XR0 151 
J 0
(-1061 2650);
DISPLAY 0.638298 (-1061 2650);
PAINT MONO (-1061 2650);
FORCEPROP 1 LAST COMMENT_BODY TRUE
J 0
(-1295 2555);
DISPLAY 0.872340 (-1295 2555);
PAINT GREEN (-1295 2555);
DISPLAY INVISIBLE (-1295 2555);
FORCEPROP 1 LAST OFFPAGE TRUE
J 0
(-925 2525);
DISPLAY 0.872340 (-925 2525);
PAINT GREEN (-925 2525);
DISPLAY INVISIBLE (-925 2525);
FORCEPROP 2 LAST PATH I54
J 0
(-1075 2725);
DISPLAY 1.021277 (-1075 2725);
PAINT ORANGE (-1075 2725);
DISPLAY INVISIBLE (-1075 2725);
FORCEPROP 2 LAST CDS_LIB mstr_standard
J 0
(-1250 2650);
PAINT MONO (-1250 2650);
DISPLAY INVISIBLE (-1250 2650);
FORCEADD OFFPAGE..2
(-1250 2600);
FORCEPROP 2 LAST $XR0 151 
J 0
(-1061 2600);
DISPLAY 0.638298 (-1061 2600);
PAINT MONO (-1061 2600);
FORCEPROP 1 LAST COMMENT_BODY TRUE
J 0
(-1295 2505);
DISPLAY 0.872340 (-1295 2505);
PAINT GREEN (-1295 2505);
DISPLAY INVISIBLE (-1295 2505);
FORCEPROP 1 LAST OFFPAGE TRUE
J 0
(-925 2475);
DISPLAY 0.872340 (-925 2475);
PAINT GREEN (-925 2475);
DISPLAY INVISIBLE (-925 2475);
FORCEPROP 2 LAST CDS_LIB mstr_standard
J 0
(-1250 2600);
PAINT MONO (-1250 2600);
DISPLAY INVISIBLE (-1250 2600);
FORCEPROP 2 LAST PATH I55
J 0
(-1075 2675);
DISPLAY 1.021277 (-1075 2675);
PAINT ORANGE (-1075 2675);
DISPLAY INVISIBLE (-1075 2675);
FORCEADD OFFPAGE..2
(-1250 1650);
FORCEPROP 2 LAST $XR0 142 
J 0
(-1061 1650);
DISPLAY 0.638298 (-1061 1650);
PAINT MONO (-1061 1650);
FORCEPROP 1 LAST COMMENT_BODY TRUE
J 0
(-1295 1555);
DISPLAY 0.872340 (-1295 1555);
PAINT GREEN (-1295 1555);
DISPLAY INVISIBLE (-1295 1555);
FORCEPROP 1 LAST OFFPAGE TRUE
J 0
(-925 1525);
DISPLAY 0.872340 (-925 1525);
PAINT GREEN (-925 1525);
DISPLAY INVISIBLE (-925 1525);
FORCEPROP 2 LAST PATH I63
J 0
(-925 1700);
DISPLAY 1.021277 (-925 1700);
PAINT ORANGE (-925 1700);
DISPLAY INVISIBLE (-925 1700);
FORCEPROP 2 LAST CDS_LIB mstr_standard
J 0
(-1250 1650);
PAINT MONO (-1250 1650);
DISPLAY INVISIBLE (-1250 1650);
FORCEADD RES..2
(-1550 1400);
FORCEPROP 1 LAST PACK_TYPE 0402
J 0
(-1510 1225);
DISPLAY 0.617021 (-1510 1225);
PAINT SKYBLUE (-1510 1225);
FORCEPROP 1 LAST TOLERANCE 1%
J 0
(-1505 1425);
DISPLAY 0.617021 (-1505 1425);
PAINT SKYBLUE (-1505 1425);
FORCEPROP 1 LASTPIN (-1550 1500) $PN 1
J 0
(-1545 1462);
DISPLAY 0.617021 (-1545 1462);
PAINT ORANGE (-1545 1462);
FORCEPROP 1 LAST WATTAGE 1/16W
J 0
(-1510 1375);
DISPLAY 0.617021 (-1510 1375);
PAINT SKYBLUE (-1510 1375);
FORCEPROP 1 LAST MATERIAL CHIP
J 0
(-1510 1325);
DISPLAY 0.617021 (-1510 1325);
PAINT SKYBLUE (-1510 1325);
FORCEPROP 1 LASTPIN (-1550 1300) $PN 2
J 0
(-1545 1310);
DISPLAY 0.617021 (-1545 1310);
PAINT ORANGE (-1545 1310);
FORCEPROP 1 LAST PART_NUMBER G21796-010
J 0
(-1510 1275);
DISPLAY 0.617021 (-1510 1275);
PAINT BLUE (-1510 1275);
FORCEPROP 1 LAST VALUE 100.0K
J 0
(-1505 1475);
DISPLAY 0.617021 (-1505 1475);
PAINT SKYBLUE (-1505 1475);
FORCEPROP 1 LAST LOCATION R25W63
J 0
(-1505 1525);
DISPLAY 0.617021 (-1505 1525);
PAINT AQUA (-1505 1525);
FORCEPROP 2 LAST CDS_LOCATION R25W63
J 0
(-1505 1525);
DISPLAY 0.617021 (-1505 1525);
PAINT AQUA (-1505 1525);
DISPLAY INVISIBLE (-1505 1525);
FORCEPROP 0 LAST CDS_SEC 1
J 0
(-1500 1575);
PAINT MONO (-1500 1575);
DISPLAY INVISIBLE (-1500 1575);
FORCEPROP 2 LAST CDS_LIB mstr_discrete
J 0
(-1550 1400);
PAINT ORANGE (-1550 1400);
DISPLAY INVISIBLE (-1550 1400);
FORCEPROP 2 LAST SEC 1
J 0
(-1500 1625);
DISPLAY 0.680851 (-1500 1625);
PAINT MONO (-1500 1625);
DISPLAY INVISIBLE (-1500 1625);
FORCEPROP 2 LAST SEC_TYPE 0402
J 0
(-1500 1625);
DISPLAY 1.021277 (-1500 1625);
PAINT ORANGE (-1500 1625);
DISPLAY INVISIBLE (-1500 1625);
FORCEPROP 0 LAST BOM_COST SM_CONTROLLER
J 0
(-1500 1725);
DISPLAY 1.021277 (-1500 1725);
PAINT ORANGE (-1500 1725);
DISPLAY INVISIBLE (-1500 1725);
FORCEPROP 0 LAST ROOM BMC
J 0
(-1500 1625);
DISPLAY 0.617021 (-1500 1625);
PAINT ORANGE (-1500 1625);
DISPLAY INVISIBLE (-1500 1625);
FORCEPROP 1 LAST PATH I65
J 0
(-1500 1575);
DISPLAY 0.978723 (-1500 1575);
PAINT WHITE (-1500 1575);
DISPLAY INVISIBLE (-1500 1575);
FORCEADD GND..1
(-1550 1200);
FORCEPROP 3 LASTPIN (-1550 1250) SIG_NAME GND\g
J 0
(-1540 1260);
DISPLAY 0.659574 (-1540 1260);
PAINT MONO (-1540 1260);
DISPLAY INVISIBLE (-1540 1260);
FORCEPROP 1 LAST HDL_POWER GND
J 0
(-1550 1350);
DISPLAY 0.872340 (-1550 1350);
PAINT GREEN (-1550 1350);
DISPLAY INVISIBLE (-1550 1350);
FORCEPROP 1 LAST BODY_TYPE PLUMBING
J 0
(-1595 1157);
DISPLAY 0.340426 (-1595 1157);
PAINT GREEN (-1595 1157);
DISPLAY INVISIBLE (-1595 1157);
FORCEPROP 1 LAST PATH I66
J 0
(-1475 1200);
DISPLAY 0.872340 (-1475 1200);
PAINT AQUA (-1475 1200);
DISPLAY INVISIBLE (-1475 1200);
FORCEPROP 1 LAST SIZE 1B
J 0
(-1475 1150);
DISPLAY 0.872340 (-1475 1150);
PAINT AQUA (-1475 1150);
DISPLAY INVISIBLE (-1475 1150);
FORCEPROP 1 LAST VOLTAGE 0.0V
J 0
(-1595 1157);
DISPLAY 0.340426 (-1595 1157);
PAINT SKYBLUE (-1595 1157);
DISPLAY INVISIBLE (-1595 1157);
FORCEPROP 2 LAST CDS_LIB mstr_symbols
J 0
(-1550 1200);
PAINT ORANGE (-1550 1200);
DISPLAY INVISIBLE (-1550 1200);
FORCEADD RES..1
(-6350 2350);
FORCEPROP 1 LAST LOCATION R25W81
J 0
(-6725 2300);
DISPLAY 0.617021 (-6725 2300);
PAINT AQUA (-6725 2300);
FORCEPROP 1 LAST WATTAGE 1/16W
J 0
(-6325 2300);
DISPLAY 0.638298 (-6325 2300);
PAINT SKYBLUE (-6325 2300);
FORCEPROP 1 LAST MATERIAL CHIP
J 0
(-6150 2300);
DISPLAY 0.617021 (-6150 2300);
PAINT SKYBLUE (-6150 2300);
FORCEPROP 1 LAST VALUE 33.2
J 2
(-6450 2300);
DISPLAY 0.617021 (-6450 2300);
PAINT SKYBLUE (-6450 2300);
FORCEPROP 1 LASTPIN (-6250 2350) $PN 2
J 0
(-6288 2362);
DISPLAY 0.617021 (-6288 2362);
PAINT ORANGE (-6288 2362);
FORCEPROP 1 LAST PACK_TYPE 0402
J 0
(-6025 2300);
DISPLAY 0.638298 (-6025 2300);
PAINT SKYBLUE (-6025 2300);
FORCEPROP 1 LAST PART_NUMBER G21796-074
J 0
(-5875 2300);
DISPLAY 0.638298 (-5875 2300);
PAINT BLUE (-5875 2300);
FORCEPROP 1 LAST TOLERANCE 1%
J 0
(-6425 2300);
DISPLAY 0.617021 (-6425 2300);
PAINT SKYBLUE (-6425 2300);
FORCEPROP 1 LASTPIN (-6450 2350) $PN 1
J 0
(-6438 2362);
DISPLAY 0.617021 (-6438 2362);
PAINT ORANGE (-6438 2362);
FORCEPROP 2 LAST CDS_LOCATION R25W81
J 0
(-6425 2275);
DISPLAY 0.617021 (-6425 2275);
PAINT AQUA (-6425 2275);
DISPLAY INVISIBLE (-6425 2275);
FORCEPROP 2 LAST CDS_LIB mstr_discrete
J 0
(-6350 2350);
PAINT ORANGE (-6350 2350);
DISPLAY INVISIBLE (-6350 2350);
FORCEPROP 2 LAST SEC_TYPE 0402
J 0
(-6400 2550);
DISPLAY 1.021277 (-6400 2550);
PAINT ORANGE (-6400 2550);
DISPLAY INVISIBLE (-6400 2550);
FORCEPROP 2 LAST SEC 1
J 0
(-6400 2550);
PAINT MONO (-6400 2550);
DISPLAY INVISIBLE (-6400 2550);
FORCEPROP 0 LAST ROOM BMC
J 0
(-6150 2400);
DISPLAY 1.021277 (-6150 2400);
PAINT ORANGE (-6150 2400);
DISPLAY INVISIBLE (-6150 2400);
FORCEPROP 0 LAST BOM_COST SM_CONTROLLER
J 0
(-6150 2450);
DISPLAY 1.021277 (-6150 2450);
PAINT ORANGE (-6150 2450);
DISPLAY INVISIBLE (-6150 2450);
FORCEPROP 1 LAST PATH I67
J 0
(-6400 2500);
DISPLAY 0.978723 (-6400 2500);
PAINT WHITE (-6400 2500);
DISPLAY INVISIBLE (-6400 2500);
FORCEADD RES..1
(-6350 2500);
FORCEPROP 1 LAST WATTAGE 1/16W
J 0
(-6325 2550);
DISPLAY 0.638298 (-6325 2550);
PAINT SKYBLUE (-6325 2550);
FORCEPROP 1 LASTPIN (-6250 2500) $PN 2
J 0
(-6288 2512);
DISPLAY 0.617021 (-6288 2512);
PAINT ORANGE (-6288 2512);
FORCEPROP 1 LAST TOLERANCE 1%
J 0
(-6425 2550);
DISPLAY 0.617021 (-6425 2550);
PAINT SKYBLUE (-6425 2550);
FORCEPROP 1 LAST VALUE 33.2
J 0
(-6550 2550);
DISPLAY 0.617021 (-6550 2550);
PAINT SKYBLUE (-6550 2550);
FORCEPROP 1 LAST PART_NUMBER G21796-074
J 0
(-5875 2550);
DISPLAY 0.638298 (-5875 2550);
PAINT BLUE (-5875 2550);
FORCEPROP 1 LAST LOCATION R25W82
J 0
(-6725 2550);
DISPLAY 0.617021 (-6725 2550);
PAINT AQUA (-6725 2550);
FORCEPROP 1 LASTPIN (-6450 2500) $PN 1
J 0
(-6438 2512);
DISPLAY 0.617021 (-6438 2512);
PAINT ORANGE (-6438 2512);
FORCEPROP 1 LAST MATERIAL CHIP
J 0
(-6150 2550);
DISPLAY 0.617021 (-6150 2550);
PAINT SKYBLUE (-6150 2550);
FORCEPROP 1 LAST PACK_TYPE 0402
J 0
(-6025 2550);
DISPLAY 0.638298 (-6025 2550);
PAINT SKYBLUE (-6025 2550);
FORCEPROP 2 LAST CDS_LOCATION R25W82
J 0
(-6400 2550);
DISPLAY 0.617021 (-6400 2550);
PAINT AQUA (-6400 2550);
DISPLAY INVISIBLE (-6400 2550);
FORCEPROP 2 LAST CDS_LIB mstr_discrete
J 0
(-6350 2500);
PAINT ORANGE (-6350 2500);
DISPLAY INVISIBLE (-6350 2500);
FORCEPROP 0 LAST ROOM BMC
J 0
(-6400 2600);
DISPLAY 1.021277 (-6400 2600);
PAINT ORANGE (-6400 2600);
DISPLAY INVISIBLE (-6400 2600);
FORCEPROP 0 LAST BOM_COST SM_CONTROLLER
J 0
(-6400 2650);
DISPLAY 1.021277 (-6400 2650);
PAINT ORANGE (-6400 2650);
DISPLAY INVISIBLE (-6400 2650);
FORCEPROP 2 LAST SEC_TYPE 0402
J 0
(-6400 2700);
DISPLAY 1.021277 (-6400 2700);
PAINT ORANGE (-6400 2700);
DISPLAY INVISIBLE (-6400 2700);
FORCEPROP 2 LAST SEC 1
J 0
(-6400 2700);
PAINT MONO (-6400 2700);
DISPLAY INVISIBLE (-6400 2700);
FORCEPROP 1 LAST PATH I68
J 0
(-6400 2650);
DISPLAY 0.978723 (-6400 2650);
PAINT WHITE (-6400 2650);
DISPLAY INVISIBLE (-6400 2650);
FORCEADD RES..1
(-6350 1750);
FORCEPROP 1 LAST TOLERANCE 5%
J 0
(-6600 1800);
DISPLAY 0.617021 (-6600 1800);
PAINT SKYBLUE (-6600 1800);
FORCEPROP 1 LAST PART_NUMBER G21497-005
J 0
(-6225 1800);
DISPLAY 0.617021 (-6225 1800);
PAINT BLUE (-6225 1800);
FORCEPROP 1 LASTPIN (-6250 1750) $PN 2
J 0
(-6288 1762);
DISPLAY 0.617021 (-6288 1762);
PAINT ORANGE (-6288 1762);
FORCEPROP 1 LAST MATERIAL CHIP
J 0
(-6375 1800);
DISPLAY 0.617021 (-6375 1800);
PAINT SKYBLUE (-6375 1800);
FORCEPROP 1 LAST WATTAGE 1/16W
J 0
(-6525 1800);
DISPLAY 0.617021 (-6525 1800);
PAINT SKYBLUE (-6525 1800);
FORCEPROP 1 LAST VALUE 0.0
J 0
(-6700 1800);
DISPLAY 0.617021 (-6700 1800);
PAINT SKYBLUE (-6700 1800);
FORCEPROP 1 LASTPIN (-6450 1750) $PN 1
J 0
(-6438 1762);
DISPLAY 0.617021 (-6438 1762);
PAINT ORANGE (-6438 1762);
FORCEPROP 1 LAST PACK_TYPE 0402
J 0
(-5975 1800);
DISPLAY 0.617021 (-5975 1800);
PAINT SKYBLUE (-5975 1800);
FORCEPROP 1 LAST LOCATION R25W74
J 0
(-6900 1800);
DISPLAY 0.617021 (-6900 1800);
PAINT AQUA (-6900 1800);
FORCEPROP 1 LAST PATH I70
J 0
(-6400 1900);
DISPLAY 0.978723 (-6400 1900);
PAINT WHITE (-6400 1900);
DISPLAY INVISIBLE (-6400 1900);
FORCEPROP 0 LAST ROOM BMC
J 0
(-6400 1900);
DISPLAY 1.021277 (-6400 1900);
PAINT ORANGE (-6400 1900);
DISPLAY INVISIBLE (-6400 1900);
FORCEPROP 2 LAST BOM_COST SM_CONTROLLER
J 0
(-6288 1802);
DISPLAY 0.787234 (-6288 1802);
PAINT SKYBLUE (-6288 1802);
DISPLAY INVISIBLE (-6288 1802);
FORCEPROP 2 LAST SEC_TYPE 0402
J 0
(-6400 1950);
DISPLAY 1.021277 (-6400 1950);
PAINT ORANGE (-6400 1950);
DISPLAY INVISIBLE (-6400 1950);
FORCEPROP 2 LAST SEC 1
J 0
(-6400 1950);
DISPLAY 0.680851 (-6400 1950);
PAINT MONO (-6400 1950);
DISPLAY INVISIBLE (-6400 1950);
FORCEPROP 2 LAST CDS_LOCATION R25W74
J 0
(-6400 1800);
DISPLAY 0.617021 (-6400 1800);
PAINT AQUA (-6400 1800);
DISPLAY INVISIBLE (-6400 1800);
FORCEPROP 0 LAST CDS_SEC 1
J 0
(-6400 1850);
PAINT MONO (-6400 1850);
DISPLAY INVISIBLE (-6400 1850);
FORCEPROP 2 LAST CDS_LIB mstr_discrete
J 0
(-6350 1750);
PAINT ORANGE (-6350 1750);
DISPLAY INVISIBLE (-6350 1750);
FORCEADD RES..1
(-6350 1550);
FORCEPROP 1 LAST MATERIAL CHIP
J 0
(-6375 1600);
DISPLAY 0.617021 (-6375 1600);
PAINT SKYBLUE (-6375 1600);
FORCEPROP 1 LASTPIN (-6450 1550) $PN 1
J 0
(-6438 1562);
DISPLAY 0.617021 (-6438 1562);
PAINT ORANGE (-6438 1562);
FORCEPROP 1 LAST PACK_TYPE 0402
J 0
(-5975 1600);
DISPLAY 0.617021 (-5975 1600);
PAINT SKYBLUE (-5975 1600);
FORCEPROP 1 LAST WATTAGE 1/16W
J 0
(-6525 1600);
DISPLAY 0.617021 (-6525 1600);
PAINT SKYBLUE (-6525 1600);
FORCEPROP 1 LAST TOLERANCE 1%
J 0
(-6600 1600);
DISPLAY 0.617021 (-6600 1600);
PAINT SKYBLUE (-6600 1600);
FORCEPROP 1 LASTPIN (-6250 1550) $PN 2
J 0
(-6288 1562);
DISPLAY 0.617021 (-6288 1562);
PAINT ORANGE (-6288 1562);
FORCEPROP 1 LAST LOCATION R25W72
J 0
(-6900 1600);
DISPLAY 0.617021 (-6900 1600);
PAINT AQUA (-6900 1600);
FORCEPROP 1 LAST VALUE 33.2
J 2
(-6625 1600);
DISPLAY 0.617021 (-6625 1600);
PAINT SKYBLUE (-6625 1600);
FORCEPROP 1 LAST PART_NUMBER G21796-074
J 0
(-6225 1600);
DISPLAY 0.617021 (-6225 1600);
PAINT BLUE (-6225 1600);
FORCEPROP 2 LAST CDS_LOCATION R25W72
J 0
(-6400 1600);
DISPLAY 0.617021 (-6400 1600);
PAINT AQUA (-6400 1600);
DISPLAY INVISIBLE (-6400 1600);
FORCEPROP 0 LAST BOM_COST SM_CONTROLLER
J 0
(-6400 1750);
DISPLAY 1.021277 (-6400 1750);
PAINT ORANGE (-6400 1750);
DISPLAY INVISIBLE (-6400 1750);
FORCEPROP 2 LAST SEC_TYPE 0402
J 0
(-6400 1750);
DISPLAY 1.021277 (-6400 1750);
PAINT ORANGE (-6400 1750);
DISPLAY INVISIBLE (-6400 1750);
FORCEPROP 0 LAST SEC 1
J 0
(-6400 1700);
DISPLAY 0.680851 (-6400 1700);
PAINT MONO (-6400 1700);
DISPLAY INVISIBLE (-6400 1700);
FORCEPROP 0 LAST ROOM BMC
J 0
(-6400 1700);
DISPLAY 1.021277 (-6400 1700);
PAINT ORANGE (-6400 1700);
DISPLAY INVISIBLE (-6400 1700);
FORCEPROP 2 LAST CDS_LIB mstr_discrete
J 0
(-6350 1550);
PAINT ORANGE (-6350 1550);
DISPLAY INVISIBLE (-6350 1550);
FORCEPROP 0 LAST CDS_SEC 1
J 0
(-6400 1700);
PAINT MONO (-6400 1700);
DISPLAY INVISIBLE (-6400 1700);
FORCEPROP 1 LAST PATH I71
J 0
(-6400 1700);
DISPLAY 0.978723 (-6400 1700);
PAINT WHITE (-6400 1700);
DISPLAY INVISIBLE (-6400 1700);
FORCEADD RES..1
(-6350 1650);
FORCEPROP 1 LAST VALUE 33.2
J 2
(-6625 1700);
DISPLAY 0.617021 (-6625 1700);
PAINT SKYBLUE (-6625 1700);
FORCEPROP 1 LAST PACK_TYPE 0402
J 0
(-5975 1700);
DISPLAY 0.617021 (-5975 1700);
PAINT SKYBLUE (-5975 1700);
FORCEPROP 1 LAST TOLERANCE 1%
J 0
(-6600 1700);
DISPLAY 0.617021 (-6600 1700);
PAINT SKYBLUE (-6600 1700);
FORCEPROP 1 LASTPIN (-6450 1650) $PN 1
J 0
(-6438 1662);
DISPLAY 0.617021 (-6438 1662);
PAINT ORANGE (-6438 1662);
FORCEPROP 1 LAST PART_NUMBER G21796-074
J 0
(-6225 1700);
DISPLAY 0.617021 (-6225 1700);
PAINT BLUE (-6225 1700);
FORCEPROP 1 LASTPIN (-6250 1650) $PN 2
J 0
(-6288 1662);
DISPLAY 0.617021 (-6288 1662);
PAINT ORANGE (-6288 1662);
FORCEPROP 1 LAST WATTAGE 1/16W
J 0
(-6525 1700);
DISPLAY 0.617021 (-6525 1700);
PAINT SKYBLUE (-6525 1700);
FORCEPROP 1 LAST MATERIAL CHIP
J 0
(-6375 1700);
DISPLAY 0.617021 (-6375 1700);
PAINT SKYBLUE (-6375 1700);
FORCEPROP 1 LAST LOCATION R25W73
J 0
(-6900 1700);
DISPLAY 0.617021 (-6900 1700);
PAINT AQUA (-6900 1700);
FORCEPROP 2 LAST CDS_LOCATION R25W73
J 0
(-6400 1700);
DISPLAY 0.617021 (-6400 1700);
PAINT AQUA (-6400 1700);
DISPLAY INVISIBLE (-6400 1700);
FORCEPROP 2 LAST SEC_TYPE 0402
J 0
(-6400 1850);
DISPLAY 1.021277 (-6400 1850);
PAINT ORANGE (-6400 1850);
DISPLAY INVISIBLE (-6400 1850);
FORCEPROP 0 LAST BOM_COST SM_CONTROLLER
J 0
(-6400 1850);
DISPLAY 1.021277 (-6400 1850);
PAINT ORANGE (-6400 1850);
DISPLAY INVISIBLE (-6400 1850);
FORCEPROP 0 LAST SEC 1
J 0
(-6400 1800);
DISPLAY 0.680851 (-6400 1800);
PAINT MONO (-6400 1800);
DISPLAY INVISIBLE (-6400 1800);
FORCEPROP 0 LAST ROOM BMC
J 0
(-6400 1800);
DISPLAY 1.021277 (-6400 1800);
PAINT ORANGE (-6400 1800);
DISPLAY INVISIBLE (-6400 1800);
FORCEPROP 2 LAST CDS_LIB mstr_discrete
J 0
(-6350 1650);
PAINT ORANGE (-6350 1650);
DISPLAY INVISIBLE (-6350 1650);
FORCEPROP 0 LAST CDS_SEC 1
J 0
(-6400 1800);
PAINT MONO (-6400 1800);
DISPLAY INVISIBLE (-6400 1800);
FORCEPROP 1 LAST PATH I73
J 0
(-6400 1800);
DISPLAY 0.978723 (-6400 1800);
PAINT WHITE (-6400 1800);
DISPLAY INVISIBLE (-6400 1800);
FORCEADD RES..1
(-6850 1350);
FORCEPROP 1 LAST LOCATION R3N24
J 0
(-6700 1350);
DISPLAY 0.617021 (-6700 1350);
PAINT AQUA (-6700 1350);
FORCEPROP 1 LASTPIN (-6950 1350) $PN 1
J 0
(-6938 1362);
DISPLAY 0.638298 (-6938 1362);
PAINT ORANGE (-6938 1362);
FORCEPROP 1 LASTPIN (-6750 1350) $PN 2
J 0
(-6788 1362);
DISPLAY 0.638298 (-6788 1362);
PAINT ORANGE (-6788 1362);
FORCEPROP 1 LAST TOLERANCE 1%
J 0
(-7350 1350);
DISPLAY 0.617021 (-7350 1350);
PAINT SKYBLUE (-7350 1350);
FORCEPROP 1 LAST PART_NUMBER G21796-074
J 0
(-7750 1350);
DISPLAY 0.617021 (-7750 1350);
PAINT BLUE (-7750 1350);
FORCEPROP 1 LAST PACK_TYPE 0402
J 0
(-6350 1350);
DISPLAY 0.617021 (-6350 1350);
PAINT SKYBLUE (-6350 1350);
FORCEPROP 1 LAST VALUE 33.2
J 2
(-6400 1350);
DISPLAY 0.617021 (-6400 1350);
PAINT SKYBLUE (-6400 1350);
FORCEPROP 1 LAST MATERIAL CHIP
J 0
(-7250 1350);
DISPLAY 0.617021 (-7250 1350);
PAINT SKYBLUE (-7250 1350);
FORCEPROP 1 LAST WATTAGE 1/16W
J 0
(-7500 1350);
DISPLAY 0.617021 (-7500 1350);
PAINT SKYBLUE (-7500 1350);
FORCEPROP 0 LAST SEC 1
J 0
(-6775 1400);
DISPLAY 0.680851 (-6775 1400);
PAINT MONO (-6775 1400);
DISPLAY INVISIBLE (-6775 1400);
FORCEPROP 2 LAST SEC_TYPE 0402
J 0
(-6900 1550);
DISPLAY 1.021277 (-6900 1550);
PAINT ORANGE (-6900 1550);
DISPLAY INVISIBLE (-6900 1550);
FORCEPROP 1 LAST PATH I74
J 0
(-6900 1500);
DISPLAY 0.978723 (-6900 1500);
PAINT WHITE (-6900 1500);
DISPLAY INVISIBLE (-6900 1500);
FORCEPROP 0 LAST ROOM BMC
J 0
(-6875 1475);
DISPLAY 1.021277 (-6875 1475);
PAINT ORANGE (-6875 1475);
DISPLAY INVISIBLE (-6875 1475);
FORCEPROP 0 LAST BOM_COST SB
J 0
(-6875 1575);
DISPLAY 1.021277 (-6875 1575);
PAINT ORANGE (-6875 1575);
DISPLAY INVISIBLE (-6875 1575);
FORCEPROP 2 LAST CDS_LIB mstr_discrete
J 0
(-6850 1350);
PAINT MONO (-6850 1350);
DISPLAY INVISIBLE (-6850 1350);
FORCEADD RES..1
(-6850 1250);
FORCEPROP 1 LAST PACK_TYPE 0402
J 0
(-6350 1250);
DISPLAY 0.617021 (-6350 1250);
PAINT SKYBLUE (-6350 1250);
FORCEPROP 1 LASTPIN (-6950 1250) $PN 1
J 0
(-6938 1262);
DISPLAY 0.638298 (-6938 1262);
PAINT ORANGE (-6938 1262);
FORCEPROP 1 LAST PART_NUMBER G21796-074
J 0
(-7750 1250);
DISPLAY 0.617021 (-7750 1250);
PAINT BLUE (-7750 1250);
FORCEPROP 1 LAST WATTAGE 1/16W
J 0
(-7500 1250);
DISPLAY 0.617021 (-7500 1250);
PAINT SKYBLUE (-7500 1250);
FORCEPROP 1 LASTPIN (-6750 1250) $PN 2
J 0
(-6788 1262);
DISPLAY 0.638298 (-6788 1262);
PAINT ORANGE (-6788 1262);
FORCEPROP 1 LAST LOCATION R3N26
J 0
(-6700 1250);
DISPLAY 0.617021 (-6700 1250);
PAINT AQUA (-6700 1250);
FORCEPROP 1 LAST VALUE 33.2
J 2
(-6400 1250);
DISPLAY 0.617021 (-6400 1250);
PAINT SKYBLUE (-6400 1250);
FORCEPROP 1 LAST TOLERANCE 1%
J 0
(-7350 1250);
DISPLAY 0.617021 (-7350 1250);
PAINT SKYBLUE (-7350 1250);
FORCEPROP 1 LAST MATERIAL CHIP
J 0
(-7250 1250);
DISPLAY 0.617021 (-7250 1250);
PAINT SKYBLUE (-7250 1250);
FORCEPROP 0 LAST SEC 1
J 0
(-6750 1300);
DISPLAY 0.680851 (-6750 1300);
PAINT MONO (-6750 1300);
DISPLAY INVISIBLE (-6750 1300);
FORCEPROP 2 LAST SEC_TYPE 0402
J 0
(-6900 1450);
DISPLAY 1.021277 (-6900 1450);
PAINT ORANGE (-6900 1450);
DISPLAY INVISIBLE (-6900 1450);
FORCEPROP 0 LAST ROOM BMC
J 0
(-6875 1375);
DISPLAY 1.021277 (-6875 1375);
PAINT ORANGE (-6875 1375);
DISPLAY INVISIBLE (-6875 1375);
FORCEPROP 0 LAST BOM_COST SB
J 0
(-6875 1475);
DISPLAY 1.021277 (-6875 1475);
PAINT ORANGE (-6875 1475);
DISPLAY INVISIBLE (-6875 1475);
FORCEPROP 2 LAST CDS_LIB mstr_discrete
J 0
(-6850 1250);
PAINT MONO (-6850 1250);
DISPLAY INVISIBLE (-6850 1250);
FORCEPROP 1 LAST PATH I75
J 0
(-6900 1400);
DISPLAY 0.978723 (-6900 1400);
PAINT WHITE (-6900 1400);
DISPLAY INVISIBLE (-6900 1400);
FORCEADD RES..2
(-6250 850);
FORCEPROP 1 LAST WATTAGE 1/16W
J 0
(-6210 825);
DISPLAY 0.617021 (-6210 825);
PAINT SKYBLUE (-6210 825);
FORCEPROP 1 LAST VALUE 100.0K
J 0
(-6205 925);
DISPLAY 0.617021 (-6205 925);
PAINT SKYBLUE (-6205 925);
FORCEPROP 1 LAST PACK_TYPE 0402
J 0
(-6210 675);
DISPLAY 0.617021 (-6210 675);
PAINT SKYBLUE (-6210 675);
FORCEPROP 1 LAST TOLERANCE 1%
J 0
(-6205 875);
DISPLAY 0.617021 (-6205 875);
PAINT SKYBLUE (-6205 875);
FORCEPROP 1 LAST MATERIAL CHIP
J 0
(-6210 775);
DISPLAY 0.617021 (-6210 775);
PAINT SKYBLUE (-6210 775);
FORCEPROP 1 LAST PART_NUMBER G21796-010
J 0
(-6210 725);
DISPLAY 0.617021 (-6210 725);
PAINT BLUE (-6210 725);
FORCEPROP 0 LAST POP NOPOP
J 0
(-6200 625);
DISPLAY 0.510638 (-6200 625);
PAINT RED (-6200 625);
FORCEPROP 1 LAST LOCATION R25W66
J 0
(-6205 975);
DISPLAY 0.617021 (-6205 975);
PAINT AQUA (-6205 975);
FORCEPROP 2 LAST CDS_SEC 1
J 0
(-6200 1075);
DISPLAY 1.021277 (-6200 1075);
PAINT ORANGE (-6200 1075);
DISPLAY INVISIBLE (-6200 1075);
FORCEPROP 2 LAST $SEC 1
J 0
(-6200 1075);
DISPLAY 0.680851 (-6200 1075);
PAINT MONO (-6200 1075);
DISPLAY INVISIBLE (-6200 1075);
FORCEPROP 2 LAST ROOM BMC
J 0
(-6200 1025);
PAINT MONO (-6200 1025);
DISPLAY INVISIBLE (-6200 1025);
FORCEPROP 2 LAST CDS_LIB mstr_discrete
J 0
(-6250 850);
PAINT ORANGE (-6250 850);
DISPLAY INVISIBLE (-6250 850);
FORCEPROP 1 LASTPIN (-6250 950) $PN 1
J 0
(-6245 912);
DISPLAY 0.787234 (-6245 912);
PAINT ORANGE (-6245 912);
DISPLAY INVISIBLE (-6245 912);
FORCEPROP 1 LASTPIN (-6250 750) $PN 2
J 0
(-6245 760);
DISPLAY 0.787234 (-6245 760);
PAINT ORANGE (-6245 760);
DISPLAY INVISIBLE (-6245 760);
FORCEPROP 1 LAST PATH I76
J 0
(-6200 1025);
DISPLAY 0.978723 (-6200 1025);
PAINT WHITE (-6200 1025);
DISPLAY INVISIBLE (-6200 1025);
FORCEPROP 2 LAST CDS_LOCATION R25W66
J 0
(-6205 975);
DISPLAY 0.617021 (-6205 975);
PAINT AQUA (-6205 975);
DISPLAY INVISIBLE (-6205 975);
FORCEADD GND..1
(-6250 650);
FORCEPROP 3 LASTPIN (-6250 700) SIG_NAME GND\g
J 0
(-6240 710);
DISPLAY 0.659574 (-6240 710);
PAINT MONO (-6240 710);
DISPLAY INVISIBLE (-6240 710);
FORCEPROP 1 LAST HDL_POWER GND
J 0
(-6250 800);
DISPLAY 0.872340 (-6250 800);
PAINT GREEN (-6250 800);
DISPLAY INVISIBLE (-6250 800);
FORCEPROP 1 LAST BODY_TYPE PLUMBING
J 0
(-6295 607);
DISPLAY 0.340426 (-6295 607);
PAINT GREEN (-6295 607);
DISPLAY INVISIBLE (-6295 607);
FORCEPROP 1 LAST VOLTAGE 0.0V
J 0
(-6295 607);
DISPLAY 0.340426 (-6295 607);
PAINT SKYBLUE (-6295 607);
DISPLAY INVISIBLE (-6295 607);
FORCEPROP 2 LAST CDS_LIB mstr_symbols
J 0
(-6250 650);
PAINT ORANGE (-6250 650);
DISPLAY INVISIBLE (-6250 650);
FORCEPROP 1 LAST SIZE 1B
J 0
(-6175 600);
DISPLAY 0.872340 (-6175 600);
PAINT AQUA (-6175 600);
DISPLAY INVISIBLE (-6175 600);
FORCEPROP 1 LAST PATH I77
J 0
(-6175 650);
DISPLAY 0.872340 (-6175 650);
PAINT AQUA (-6175 650);
DISPLAY INVISIBLE (-6175 650);
FORCEADD RES..1
(-6350 2650);
FORCEPROP 1 LAST LOCATION R1U7
J 0
(-6425 3025);
DISPLAY 0.617021 (-6425 3025);
PAINT AQUA (-6425 3025);
FORCEPROP 1 LAST VALUE 10.0K
J 2
(-6325 2975);
DISPLAY 0.617021 (-6325 2975);
PAINT SKYBLUE (-6325 2975);
FORCEPROP 1 LAST PART_NUMBER G21796-016
J 0
(-6425 2775);
DISPLAY 0.617021 (-6425 2775);
PAINT BLUE (-6425 2775);
FORCEPROP 1 LASTPIN (-6450 2650) $PN 1
J 0
(-6438 2662);
DISPLAY 0.617021 (-6438 2662);
PAINT ORANGE (-6438 2662);
FORCEPROP 1 LAST MATERIAL CHIP
J 0
(-6425 2825);
DISPLAY 0.617021 (-6425 2825);
PAINT SKYBLUE (-6425 2825);
FORCEPROP 1 LAST PACK_TYPE 0402
J 0
(-6425 2725);
DISPLAY 0.617021 (-6425 2725);
PAINT SKYBLUE (-6425 2725);
FORCEPROP 1 LAST WATTAGE 1/16W
J 2
(-6300 2875);
DISPLAY 0.617021 (-6300 2875);
PAINT SKYBLUE (-6300 2875);
FORCEPROP 1 LAST TOLERANCE 1%
J 0
(-6425 2925);
DISPLAY 0.617021 (-6425 2925);
PAINT SKYBLUE (-6425 2925);
FORCEPROP 1 LASTPIN (-6250 2650) $PN 2
J 0
(-6288 2662);
DISPLAY 0.617021 (-6288 2662);
PAINT ORANGE (-6288 2662);
FORCEPROP 1 LAST PATH I78
J 0
(-6400 2800);
DISPLAY 0.978723 (-6400 2800);
PAINT WHITE (-6400 2800);
DISPLAY INVISIBLE (-6400 2800);
FORCEPROP 2 LAST CDS_LOCATION R1U7
J 0
(-6400 2700);
DISPLAY 0.617021 (-6400 2700);
PAINT AQUA (-6400 2700);
DISPLAY INVISIBLE (-6400 2700);
FORCEPROP 2 LAST CDS_LIB mstr_discrete
J 0
(-6350 2650);
PAINT ORANGE (-6350 2650);
DISPLAY INVISIBLE (-6350 2650);
FORCEPROP 0 LAST BOM_COST SM_CONTROLLER
J 0
(-6300 2975);
DISPLAY 1.021277 (-6300 2975);
PAINT ORANGE (-6300 2975);
DISPLAY INVISIBLE (-6300 2975);
FORCEPROP 0 LAST ROOM BMC
J 0
(-6300 2875);
DISPLAY 1.021277 (-6300 2875);
PAINT ORANGE (-6300 2875);
DISPLAY INVISIBLE (-6300 2875);
FORCEPROP 2 LAST SEC_TYPE 0402
J 0
(-6400 2850);
DISPLAY 1.021277 (-6400 2850);
PAINT ORANGE (-6400 2850);
DISPLAY INVISIBLE (-6400 2850);
FORCEPROP 2 LAST SEC 1
J 0
(-6400 2850);
DISPLAY 0.680851 (-6400 2850);
PAINT MONO (-6400 2850);
DISPLAY INVISIBLE (-6400 2850);
FORCEPROP 0 LAST CDS_SEC 1
J 0
(-6400 2800);
PAINT MONO (-6400 2800);
DISPLAY INVISIBLE (-6400 2800);
FORCEADD GND..1
R 5
(-6650 2650);
FORCEPROP 3 LASTPIN (-6600 2650) SIG_NAME GND\g
J 0
(-6590 2660);
DISPLAY 0.659574 (-6590 2660);
PAINT MONO (-6590 2660);
DISPLAY INVISIBLE (-6590 2660);
FORCEPROP 1 LAST HDL_POWER GND
R 3
J 0
(-6500 2650);
DISPLAY 0.872340 (-6500 2650);
PAINT GREEN (-6500 2650);
DISPLAY INVISIBLE (-6500 2650);
FORCEPROP 1 LAST BODY_TYPE PLUMBING
R 3
J 0
(-6693 2695);
DISPLAY 0.340426 (-6693 2695);
PAINT GREEN (-6693 2695);
DISPLAY INVISIBLE (-6693 2695);
FORCEPROP 2 LAST CDS_LIB mstr_symbols
R 3
J 0
(-6650 2650);
PAINT ORANGE (-6650 2650);
DISPLAY INVISIBLE (-6650 2650);
FORCEPROP 1 LAST SIZE 1B
R 3
J 0
(-6700 2575);
DISPLAY 0.872340 (-6700 2575);
PAINT AQUA (-6700 2575);
DISPLAY INVISIBLE (-6700 2575);
FORCEPROP 1 LAST VOLTAGE 0.0V
R 3
J 0
(-6693 2695);
DISPLAY 0.340426 (-6693 2695);
PAINT SKYBLUE (-6693 2695);
DISPLAY INVISIBLE (-6693 2695);
FORCEPROP 1 LAST PATH I79
R 3
J 0
(-6650 2575);
DISPLAY 0.872340 (-6650 2575);
PAINT AQUA (-6650 2575);
DISPLAY INVISIBLE (-6650 2575);
FORCEADD OFFPAGE..1
(-7100 2450);
FORCEPROP 2 LAST $XR0 162 
J 0
(-7352 2450);
DISPLAY 0.638298 (-7352 2450);
PAINT MONO (-7352 2450);
FORCEPROP 2 LAST $XR1 246 
J 0
(-7472 2450);
DISPLAY 0.638298 (-7472 2450);
PAINT MONO (-7472 2450);
FORCEPROP 2 LAST $XR2 150 
J 0
(-7592 2450);
DISPLAY 0.638298 (-7592 2450);
PAINT MONO (-7592 2450);
FORCEPROP 1 LAST COMMENT_BODY TRUE
J 0
(-6975 2350);
DISPLAY 0.872340 (-6975 2350);
PAINT GREEN (-6975 2350);
DISPLAY INVISIBLE (-6975 2350);
FORCEPROP 1 LAST OFFPAGE TRUE
J 0
(-6775 2325);
DISPLAY 0.872340 (-6775 2325);
PAINT GREEN (-6775 2325);
DISPLAY INVISIBLE (-6775 2325);
FORCEPROP 2 LAST BOM_COST SM_CONTROLLER
J 0
(-6650 2500);
PAINT MONO (-6650 2500);
DISPLAY INVISIBLE (-6650 2500);
FORCEPROP 2 LAST ROOM BMC
J 0
(-7350 2525);
DISPLAY 1.361702 (-7350 2525);
PAINT ORANGE (-7350 2525);
DISPLAY INVISIBLE (-7350 2525);
FORCEPROP 2 LAST CDS_LIB mstr_standard
J 0
(-7100 2450);
PAINT MONO (-7100 2450);
DISPLAY INVISIBLE (-7100 2450);
FORCEPROP 2 LAST PATH I80
J 0
(-7050 2525);
DISPLAY 1.021277 (-7050 2525);
PAINT ORANGE (-7050 2525);
DISPLAY INVISIBLE (-7050 2525);
FORCEADD OFFPAGE..5
(-7100 2500);
FORCEPROP 2 LAST $XR0 150 
J 0
(-7355 2500);
DISPLAY 0.638298 (-7355 2500);
PAINT MONO (-7355 2500);
FORCEPROP 2 LAST $XR1 162 
J 0
(-7475 2500);
DISPLAY 0.638298 (-7475 2500);
PAINT MONO (-7475 2500);
FORCEPROP 2 LAST $XR2 246 
J 0
(-7595 2500);
DISPLAY 0.638298 (-7595 2500);
PAINT MONO (-7595 2500);
FORCEPROP 1 LAST COMMENT_BODY TRUE
J 0
(-7000 2425);
DISPLAY 0.872340 (-7000 2425);
PAINT GREEN (-7000 2425);
DISPLAY INVISIBLE (-7000 2425);
FORCEPROP 1 LAST OFFPAGE TRUE
J 0
(-6775 2375);
DISPLAY 0.872340 (-6775 2375);
PAINT GREEN (-6775 2375);
DISPLAY INVISIBLE (-6775 2375);
FORCEPROP 2 LAST CDS_LIB mstr_standard
J 0
(-7100 2500);
PAINT MONO (-7100 2500);
DISPLAY INVISIBLE (-7100 2500);
FORCEPROP 2 LAST PATH I81
J 0
(-7050 2575);
DISPLAY 1.021277 (-7050 2575);
PAINT ORANGE (-7050 2575);
DISPLAY INVISIBLE (-7050 2575);
FORCEADD OFFPAGE..5
(-7100 2350);
FORCEPROP 2 LAST $XR0 150 
J 0
(-7355 2350);
DISPLAY 0.638298 (-7355 2350);
PAINT MONO (-7355 2350);
FORCEPROP 2 LAST $XR1 162 
J 0
(-7475 2350);
DISPLAY 0.638298 (-7475 2350);
PAINT MONO (-7475 2350);
FORCEPROP 2 LAST $XR2 246 
J 0
(-7595 2350);
DISPLAY 0.638298 (-7595 2350);
PAINT MONO (-7595 2350);
FORCEPROP 1 LAST COMMENT_BODY TRUE
J 0
(-7000 2275);
DISPLAY 0.872340 (-7000 2275);
PAINT GREEN (-7000 2275);
DISPLAY INVISIBLE (-7000 2275);
FORCEPROP 1 LAST OFFPAGE TRUE
J 0
(-6775 2225);
DISPLAY 0.872340 (-6775 2225);
PAINT GREEN (-6775 2225);
DISPLAY INVISIBLE (-6775 2225);
FORCEPROP 2 LAST CDS_LIB mstr_standard
J 0
(-7100 2350);
PAINT MONO (-7100 2350);
DISPLAY INVISIBLE (-7100 2350);
FORCEPROP 2 LAST PATH I83
J 0
(-7050 2425);
DISPLAY 1.021277 (-7050 2425);
PAINT ORANGE (-7050 2425);
DISPLAY INVISIBLE (-7050 2425);
FORCEADD RES..1
(-6850 1400);
FORCEPROP 1 LAST TOLERANCE 1%
J 0
(-6475 1450);
DISPLAY 0.617021 (-6475 1450);
PAINT SKYBLUE (-6475 1450);
FORCEPROP 1 LAST VALUE 33.2
J 2
(-6400 1400);
DISPLAY 0.617021 (-6400 1400);
PAINT SKYBLUE (-6400 1400);
FORCEPROP 1 LAST LOCATION R25W68
J 0
(-6700 1400);
DISPLAY 0.617021 (-6700 1400);
PAINT AQUA (-6700 1400);
FORCEPROP 1 LAST WATTAGE 1/16W
J 0
(-6700 1450);
DISPLAY 0.617021 (-6700 1450);
PAINT SKYBLUE (-6700 1450);
FORCEPROP 1 LASTPIN (-6750 1400) $PN 2
J 0
(-6788 1412);
DISPLAY 0.638298 (-6788 1412);
PAINT ORANGE (-6788 1412);
FORCEPROP 1 LASTPIN (-6950 1400) $PN 1
J 0
(-6938 1412);
DISPLAY 0.638298 (-6938 1412);
PAINT ORANGE (-6938 1412);
FORCEPROP 1 LAST PART_NUMBER G21796-074
J 0
(-6975 1450);
DISPLAY 0.617021 (-6975 1450);
PAINT BLUE (-6975 1450);
FORCEPROP 1 LAST MATERIAL CHIP
J 0
(-6350 1450);
DISPLAY 0.617021 (-6350 1450);
PAINT SKYBLUE (-6350 1450);
FORCEPROP 1 LAST PACK_TYPE 0402
J 0
(-6350 1400);
DISPLAY 0.617021 (-6350 1400);
PAINT SKYBLUE (-6350 1400);
FORCEPROP 2 LAST CDS_LIB mstr_discrete
J 0
(-6850 1400);
PAINT MONO (-6850 1400);
DISPLAY INVISIBLE (-6850 1400);
FORCEPROP 0 LAST BOM_COST SB
J 0
(-6875 1625);
DISPLAY 1.021277 (-6875 1625);
PAINT ORANGE (-6875 1625);
DISPLAY INVISIBLE (-6875 1625);
FORCEPROP 0 LAST ROOM BMC
J 0
(-6875 1525);
DISPLAY 1.021277 (-6875 1525);
PAINT ORANGE (-6875 1525);
DISPLAY INVISIBLE (-6875 1525);
FORCEPROP 1 LAST PATH I84
J 0
(-6900 1550);
DISPLAY 0.978723 (-6900 1550);
PAINT WHITE (-6900 1550);
DISPLAY INVISIBLE (-6900 1550);
FORCEPROP 2 LAST SEC_TYPE 0402
J 0
(-6900 1600);
DISPLAY 1.021277 (-6900 1600);
PAINT ORANGE (-6900 1600);
DISPLAY INVISIBLE (-6900 1600);
FORCEPROP 0 LAST SEC 1
J 0
(-6650 1450);
DISPLAY 0.680851 (-6650 1450);
PAINT MONO (-6650 1450);
DISPLAY INVISIBLE (-6650 1450);
FORCEADD RES..1
(-6850 1300);
FORCEPROP 1 LAST LOCATION R25W69
J 0
(-6700 1300);
DISPLAY 0.617021 (-6700 1300);
PAINT AQUA (-6700 1300);
FORCEPROP 1 LASTPIN (-6950 1300) $PN 1
J 0
(-6938 1312);
DISPLAY 0.638298 (-6938 1312);
PAINT ORANGE (-6938 1312);
FORCEPROP 1 LASTPIN (-6750 1300) $PN 2
J 0
(-6788 1312);
DISPLAY 0.638298 (-6788 1312);
PAINT ORANGE (-6788 1312);
FORCEPROP 1 LAST PART_NUMBER G21796-074
J 0
(-7750 1300);
DISPLAY 0.617021 (-7750 1300);
PAINT BLUE (-7750 1300);
FORCEPROP 1 LAST WATTAGE 1/16W
J 0
(-7500 1300);
DISPLAY 0.617021 (-7500 1300);
PAINT SKYBLUE (-7500 1300);
FORCEPROP 1 LAST PACK_TYPE 0402
J 0
(-6350 1300);
DISPLAY 0.617021 (-6350 1300);
PAINT SKYBLUE (-6350 1300);
FORCEPROP 1 LAST VALUE 33.2
J 2
(-6400 1300);
DISPLAY 0.617021 (-6400 1300);
PAINT SKYBLUE (-6400 1300);
FORCEPROP 1 LAST TOLERANCE 1%
J 0
(-7350 1300);
DISPLAY 0.617021 (-7350 1300);
PAINT SKYBLUE (-7350 1300);
FORCEPROP 1 LAST MATERIAL CHIP
J 0
(-7250 1300);
DISPLAY 0.617021 (-7250 1300);
PAINT SKYBLUE (-7250 1300);
FORCEPROP 0 LAST ROOM BMC
J 0
(-6875 1425);
DISPLAY 1.021277 (-6875 1425);
PAINT ORANGE (-6875 1425);
DISPLAY INVISIBLE (-6875 1425);
FORCEPROP 0 LAST BOM_COST SB
J 0
(-6875 1525);
DISPLAY 1.021277 (-6875 1525);
PAINT ORANGE (-6875 1525);
DISPLAY INVISIBLE (-6875 1525);
FORCEPROP 2 LAST CDS_LIB mstr_discrete
J 0
(-6850 1300);
PAINT MONO (-6850 1300);
DISPLAY INVISIBLE (-6850 1300);
FORCEPROP 1 LAST PATH I85
J 0
(-6900 1450);
DISPLAY 0.978723 (-6900 1450);
PAINT WHITE (-6900 1450);
DISPLAY INVISIBLE (-6900 1450);
FORCEPROP 2 LAST SEC_TYPE 0402
J 0
(-6900 1500);
DISPLAY 1.021277 (-6900 1500);
PAINT ORANGE (-6900 1500);
DISPLAY INVISIBLE (-6900 1500);
FORCEPROP 0 LAST SEC 1
J 0
(-6675 1350);
DISPLAY 0.680851 (-6675 1350);
PAINT MONO (-6675 1350);
DISPLAY INVISIBLE (-6675 1350);
FORCEADD OFFPAGE..1
(-7100 1750);
FORCEPROP 2 LAST $XR0 146 
J 0
(-7352 1750);
DISPLAY 0.638298 (-7352 1750);
PAINT MONO (-7352 1750);
FORCEPROP 2 LAST $XR1 191 
J 0
(-7472 1750);
DISPLAY 0.638298 (-7472 1750);
PAINT MONO (-7472 1750);
FORCEPROP 2 LAST $XR2 134 
J 0
(-7592 1750);
DISPLAY 0.638298 (-7592 1750);
PAINT MONO (-7592 1750);
FORCEPROP 2 LAST $XR3 145 
J 0
(-7712 1750);
DISPLAY 0.638298 (-7712 1750);
PAINT MONO (-7712 1750);
FORCEPROP 2 LAST $XR4 184 
J 0
(-7832 1750);
DISPLAY 0.638298 (-7832 1750);
PAINT MONO (-7832 1750);
FORCEPROP 1 LAST COMMENT_BODY TRUE
J 0
(-6975 1650);
DISPLAY 0.872340 (-6975 1650);
PAINT GREEN (-6975 1650);
DISPLAY INVISIBLE (-6975 1650);
FORCEPROP 1 LAST OFFPAGE TRUE
J 0
(-6775 1625);
DISPLAY 0.872340 (-6775 1625);
PAINT GREEN (-6775 1625);
DISPLAY INVISIBLE (-6775 1625);
FORCEPROP 2 LAST ROOM BMC
J 0
(-7350 1825);
DISPLAY 1.361702 (-7350 1825);
PAINT ORANGE (-7350 1825);
DISPLAY INVISIBLE (-7350 1825);
FORCEPROP 2 LAST CDS_LIB mstr_standard
J 2
(-7100 1750);
PAINT ORANGE (-7100 1750);
DISPLAY INVISIBLE (-7100 1750);
FORCEPROP 2 LAST BOM_COST SM_CONTROLLER
J 0
(-6650 1800);
PAINT MONO (-6650 1800);
DISPLAY INVISIBLE (-6650 1800);
FORCEPROP 2 LAST PATH I86
J 0
(-7375 1800);
DISPLAY 1.021277 (-7375 1800);
PAINT ORANGE (-7375 1800);
DISPLAY INVISIBLE (-7375 1800);
FORCEADD OFFPAGE..3
R 2
(-7100 1650);
FORCEPROP 2 LAST $XR0 133 
J 0
(-7380 1650);
DISPLAY 0.638298 (-7380 1650);
PAINT MONO (-7380 1650);
FORCEPROP 2 LAST $XR1 119 
J 0
(-7500 1650);
DISPLAY 0.638298 (-7500 1650);
PAINT MONO (-7500 1650);
FORCEPROP 1 LAST COMMENT_BODY TRUE
J 2
(-7050 1550);
DISPLAY 1.170213 (-7050 1550);
PAINT GREEN (-7050 1550);
DISPLAY INVISIBLE (-7050 1550);
FORCEPROP 1 LAST OFFPAGE TRUE
J 2
(-7425 1525);
PAINT GREEN (-7425 1525);
DISPLAY INVISIBLE (-7425 1525);
FORCEPROP 2 LAST CDS_LIB mstr_standard
J 0
(-7100 1650);
PAINT ORANGE (-7100 1650);
DISPLAY INVISIBLE (-7100 1650);
FORCEPROP 2 LAST PATH I87
J 0
(-7375 1700);
DISPLAY 1.021277 (-7375 1700);
PAINT ORANGE (-7375 1700);
DISPLAY INVISIBLE (-7375 1700);
FORCEPROP 2 LAST ROOM BMC
J 2
(-7575 1700);
PAINT MONO (-7575 1700);
DISPLAY INVISIBLE (-7575 1700);
FORCEPROP 2 LAST BOM_COST SM_CONTROLLER
J 2
(-7575 1700);
PAINT MONO (-7575 1700);
DISPLAY INVISIBLE (-7575 1700);
FORCEADD OFFPAGE..3
R 2
(-7100 1550);
FORCEPROP 2 LAST $XR0 119 
J 0
(-7380 1550);
DISPLAY 0.638298 (-7380 1550);
PAINT MONO (-7380 1550);
FORCEPROP 1 LAST COMMENT_BODY TRUE
J 2
(-7050 1450);
DISPLAY 1.170213 (-7050 1450);
PAINT GREEN (-7050 1450);
DISPLAY INVISIBLE (-7050 1450);
FORCEPROP 1 LAST OFFPAGE TRUE
J 2
(-7425 1425);
PAINT GREEN (-7425 1425);
DISPLAY INVISIBLE (-7425 1425);
FORCEPROP 2 LAST CDS_LIB mstr_standard
J 0
(-7100 1550);
PAINT ORANGE (-7100 1550);
DISPLAY INVISIBLE (-7100 1550);
FORCEPROP 2 LAST ROOM BMC
J 2
(-7575 1600);
PAINT MONO (-7575 1600);
DISPLAY INVISIBLE (-7575 1600);
FORCEPROP 2 LAST BOM_COST SM_CONTROLLER
J 2
(-7575 1600);
PAINT MONO (-7575 1600);
DISPLAY INVISIBLE (-7575 1600);
FORCEPROP 2 LAST PATH I88
J 0
(-7375 1600);
DISPLAY 1.021277 (-7375 1600);
PAINT ORANGE (-7375 1600);
DISPLAY INVISIBLE (-7375 1600);
FORCEADD OFFPAGE..1
(-7100 1500);
FORCEPROP 2 LAST $XR0 119 
J 0
(-7526 1500);
DISPLAY 0.638298 (-7526 1500);
PAINT MONO (-7526 1500);
DISPLAY INVISIBLE (-7526 1500);
FORCEPROP 1 LAST COMMENT_BODY TRUE
J 0
(-6975 1400);
DISPLAY 0.872340 (-6975 1400);
PAINT GREEN (-6975 1400);
DISPLAY INVISIBLE (-6975 1400);
FORCEPROP 1 LAST OFFPAGE TRUE
J 0
(-6775 1375);
DISPLAY 0.872340 (-6775 1375);
PAINT GREEN (-6775 1375);
DISPLAY INVISIBLE (-6775 1375);
FORCEPROP 2 LAST ROOM BMC
J 0
(-7350 1575);
DISPLAY 1.361702 (-7350 1575);
PAINT ORANGE (-7350 1575);
DISPLAY INVISIBLE (-7350 1575);
FORCEPROP 2 LAST CDS_LIB mstr_standard
J 2
(-7100 1500);
PAINT ORANGE (-7100 1500);
DISPLAY INVISIBLE (-7100 1500);
FORCEPROP 2 LAST BOM_COST SM_CONTROLLER
J 0
(-6650 1550);
PAINT MONO (-6650 1550);
DISPLAY INVISIBLE (-6650 1550);
FORCEPROP 2 LAST PATH I89
J 0
(-7375 1550);
DISPLAY 1.021277 (-7375 1550);
PAINT ORANGE (-7375 1550);
DISPLAY INVISIBLE (-7375 1550);
FORCEADD TAP..1
R 2
(-7050 1400);
FORCEPROP 3 LASTPIN (-7000 1400) SIG_NAME LPC_LAD_IO<3>
J 0
(-6990 1410);
DISPLAY 0.659574 (-6990 1410);
PAINT MONO (-6990 1410);
DISPLAY INVISIBLE (-6990 1410);
FORCEPROP 1 LASTPIN (-7000 1400) BN 3
J 2
(-6988 1408);
DISPLAY 0.680851 (-6988 1408);
PAINT GREEN (-6988 1408);
FORCEPROP 1 LAST HDL_TAP TRUE
J 2
(-7375 1275);
DISPLAY 0.872340 (-7375 1275);
PAINT ORANGE (-7375 1275);
DISPLAY INVISIBLE (-7375 1275);
FORCEPROP 1 LAST BODY_TYPE PLUMBING
J 2
(-7050 1450);
DISPLAY 0.872340 (-7050 1450);
PAINT GREEN (-7050 1450);
DISPLAY INVISIBLE (-7050 1450);
FORCEPROP 1 LAST PATH I90
J 2
(-7048 1400);
DISPLAY 0.872340 (-7048 1400);
PAINT GREEN (-7048 1400);
DISPLAY INVISIBLE (-7048 1400);
FORCEPROP 2 LAST CDS_LIB mstr_standard
J 0
(-7050 1400);
PAINT MONO (-7050 1400);
DISPLAY INVISIBLE (-7050 1400);
FORCEADD TAP..1
R 2
(-7050 1250);
FORCEPROP 3 LASTPIN (-7000 1250) SIG_NAME LPC_LAD_IO<0>
J 0
(-6990 1260);
DISPLAY 0.659574 (-6990 1260);
PAINT MONO (-6990 1260);
DISPLAY INVISIBLE (-6990 1260);
FORCEPROP 1 LASTPIN (-7000 1250) BN 0
J 2
(-6988 1258);
DISPLAY 0.680851 (-6988 1258);
PAINT GREEN (-6988 1258);
FORCEPROP 1 LAST HDL_TAP TRUE
J 2
(-7375 1125);
DISPLAY 0.872340 (-7375 1125);
PAINT ORANGE (-7375 1125);
DISPLAY INVISIBLE (-7375 1125);
FORCEPROP 1 LAST BODY_TYPE PLUMBING
J 2
(-7050 1300);
DISPLAY 0.872340 (-7050 1300);
PAINT GREEN (-7050 1300);
DISPLAY INVISIBLE (-7050 1300);
FORCEPROP 1 LAST PATH I91
J 2
(-7048 1250);
DISPLAY 0.872340 (-7048 1250);
PAINT GREEN (-7048 1250);
DISPLAY INVISIBLE (-7048 1250);
FORCEPROP 2 LAST CDS_LIB mstr_standard
J 0
(-7050 1250);
PAINT MONO (-7050 1250);
DISPLAY INVISIBLE (-7050 1250);
FORCEADD TAP..1
R 2
(-7050 1300);
FORCEPROP 3 LASTPIN (-7000 1300) SIG_NAME LPC_LAD_IO<1>
J 0
(-6990 1310);
DISPLAY 0.659574 (-6990 1310);
PAINT MONO (-6990 1310);
DISPLAY INVISIBLE (-6990 1310);
FORCEPROP 1 LASTPIN (-7000 1300) BN 1
J 2
(-6988 1308);
DISPLAY 0.680851 (-6988 1308);
PAINT GREEN (-6988 1308);
FORCEPROP 1 LAST HDL_TAP TRUE
J 2
(-7375 1175);
DISPLAY 0.872340 (-7375 1175);
PAINT ORANGE (-7375 1175);
DISPLAY INVISIBLE (-7375 1175);
FORCEPROP 1 LAST BODY_TYPE PLUMBING
J 2
(-7050 1350);
DISPLAY 0.872340 (-7050 1350);
PAINT GREEN (-7050 1350);
DISPLAY INVISIBLE (-7050 1350);
FORCEPROP 1 LAST PATH I92
J 2
(-7048 1300);
DISPLAY 0.872340 (-7048 1300);
PAINT GREEN (-7048 1300);
DISPLAY INVISIBLE (-7048 1300);
FORCEPROP 2 LAST CDS_LIB mstr_standard
J 0
(-7050 1300);
PAINT MONO (-7050 1300);
DISPLAY INVISIBLE (-7050 1300);
FORCEADD TAP..1
R 2
(-7050 1350);
FORCEPROP 3 LASTPIN (-7000 1350) SIG_NAME LPC_LAD_IO<2>
J 0
(-6990 1360);
DISPLAY 0.659574 (-6990 1360);
PAINT MONO (-6990 1360);
DISPLAY INVISIBLE (-6990 1360);
FORCEPROP 1 LASTPIN (-7000 1350) BN 2
J 2
(-6988 1358);
DISPLAY 0.680851 (-6988 1358);
PAINT GREEN (-6988 1358);
FORCEPROP 1 LAST HDL_TAP TRUE
J 2
(-7375 1225);
DISPLAY 0.872340 (-7375 1225);
PAINT ORANGE (-7375 1225);
DISPLAY INVISIBLE (-7375 1225);
FORCEPROP 1 LAST BODY_TYPE PLUMBING
J 2
(-7050 1400);
DISPLAY 0.872340 (-7050 1400);
PAINT GREEN (-7050 1400);
DISPLAY INVISIBLE (-7050 1400);
FORCEPROP 1 LAST PATH I93
J 2
(-7048 1350);
DISPLAY 0.872340 (-7048 1350);
PAINT GREEN (-7048 1350);
DISPLAY INVISIBLE (-7048 1350);
FORCEPROP 2 LAST CDS_LIB mstr_standard
J 0
(-7050 1350);
PAINT MONO (-7050 1350);
DISPLAY INVISIBLE (-7050 1350);
FORCEADD OFFPAGE..3
R 2
(-7650 1425);
FORCEPROP 2 LAST $XR0 119 
J 0
(-7930 1425);
DISPLAY 0.638298 (-7930 1425);
PAINT MONO (-7930 1425);
FORCEPROP 1 LAST COMMENT_BODY TRUE
J 2
(-7600 1325);
DISPLAY 1.170213 (-7600 1325);
PAINT GREEN (-7600 1325);
DISPLAY INVISIBLE (-7600 1325);
FORCEPROP 1 LAST OFFPAGE TRUE
J 2
(-7975 1300);
PAINT GREEN (-7975 1300);
DISPLAY INVISIBLE (-7975 1300);
FORCEPROP 2 LAST ROOM BMC
J 2
(-8125 1475);
PAINT MONO (-8125 1475);
DISPLAY INVISIBLE (-8125 1475);
FORCEPROP 2 LAST BOM_COST SM_CONTROLLER
J 2
(-8125 1475);
PAINT MONO (-8125 1475);
DISPLAY INVISIBLE (-8125 1475);
FORCEPROP 2 LAST CDS_LIB mstr_standard
J 0
(-7650 1425);
PAINT MONO (-7650 1425);
DISPLAY INVISIBLE (-7650 1425);
FORCEPROP 2 LAST PATH I94
J 0
(-7600 1500);
DISPLAY 1.021277 (-7600 1500);
PAINT ORANGE (-7600 1500);
DISPLAY INVISIBLE (-7600 1500);
FORCEADD OFFPAGE..1
(-6500 4200);
FORCEPROP 2 LAST $XR0 150 
J 0
(-6752 4200);
DISPLAY 0.638298 (-6752 4200);
PAINT MONO (-6752 4200);
FORCEPROP 1 LAST COMMENT_BODY TRUE
J 0
(-6375 4100);
DISPLAY 0.872340 (-6375 4100);
PAINT GREEN (-6375 4100);
DISPLAY INVISIBLE (-6375 4100);
FORCEPROP 1 LAST OFFPAGE TRUE
J 0
(-6175 4075);
DISPLAY 0.872340 (-6175 4075);
PAINT GREEN (-6175 4075);
DISPLAY INVISIBLE (-6175 4075);
FORCEPROP 2 LAST CDS_LIB mstr_standard
J 0
(-6500 4200);
PAINT MONO (-6500 4200);
DISPLAY INVISIBLE (-6500 4200);
FORCEPROP 2 LAST PATH I99
J 0
(-6450 4275);
DISPLAY 1.021277 (-6450 4275);
PAINT ORANGE (-6450 4275);
DISPLAY INVISIBLE (-6450 4275);
FORCEPROP 2 LAST BOM_COST SM_CONTROLLER
J 0
(-6050 4250);
PAINT MONO (-6050 4250);
DISPLAY INVISIBLE (-6050 4250);
FORCEPROP 2 LAST ROOM BMC
J 0
(-6750 4275);
DISPLAY 1.361702 (-6750 4275);
PAINT ORANGE (-6750 4275);
DISPLAY INVISIBLE (-6750 4275);
FORCEADD INTEL_CORP_BPAGE..1
(0 0);
FORCEPROP 1 LAST CDS_CON_LAST_MODIFIED Fri Jun 16 17:48:55 2017
J 0
(-1425 325);
DISPLAY 1.361702 (-1425 325);
PAINT GREEN (-1425 325);
DISPLAY INVISIBLE (-1425 325);
FORCEPROP 1 LAST CUSTOM_TXT_CDS <CURRENT_DESIGN_SHEET> OF <TOTAL_DESIGN_SHEETS>
J 0
(-500 25);
PAINT ORANGE (-500 25);
FORCEPROP 1 LAST CUSTOM_TXT_CDS <CON_LAST_MODIFIED>
J 0
(-4000 100);
PAINT ORANGE (-4000 100);
FORCEPROP 2 LAST CUSTOM_TXT_CDS <XR_PAGE_TITLE>
J 0
(-7890 5250);
DISPLAY 0.638298 (-7890 5250);
PAINT PINK (-7890 5250);
DISPLAY INVISIBLE (-7890 5250);
FORCEPROP 1 LAST SCH_TITLE BMC (4 & 5 OF 7)
J 0
(-7950 50);
DISPLAY 1.212766 (-7950 50);
PAINT ORANGE (-7950 50);
FORCEPROP 2 LAST CDS_XR_PAGE_TITLE CR-146 : @BASEBOARD_FAB2_LIB.BASEBOARD_FAB2(SCH_1):PAGE146
J 0
(-7890 5250);
DISPLAY 0.638298 (-7890 5250);
PAINT PINK (-7890 5250);
DISPLAY INVISIBLE (-7890 5250);
FORCEPROP 1 LAST COMMENT_BODY TRUE
J 0
(12 12);
DISPLAY 0.617021 (12 12);
PAINT GREEN (12 12);
DISPLAY INVISIBLE (12 12);
FORCEPROP 2 LAST PAGE_BORDER TRUE
J 0
(-7890 5250);
DISPLAY 0.851064 (-7890 5250);
PAINT PINK (-7890 5250);
DISPLAY INVISIBLE (-7890 5250);
FORCEPROP 2 LAST CDS_LIB mstr_symbols
J 0
(0 0);
DISPLAY 1.361702 (0 0);
PAINT ORANGE (0 0);
DISPLAY INVISIBLE (0 0);
FORCEADD CAD_NOTE..1
(-7750 1925);
FORCEPROP 0 LAST L1 PLACE RESISTORS CLOSE TO BMC
J 0
(-7525 1875);
DISPLAY 0.680851 (-7525 1875);
PAINT ORANGE (-7525 1875);
FORCEPROP 1 LAST COMMENT_BODY TRUE
J 0
(-7725 2025);
DISPLAY 0.978723 (-7725 2025);
PAINT ORANGE (-7725 2025);
DISPLAY INVISIBLE (-7725 2025);
FORCEPROP 2 LAST CDS_LIB mstr_symbols
J 0
(-7750 1925);
PAINT ORANGE (-7750 1925);
DISPLAY INVISIBLE (-7750 1925);
WIRE 16 -1 (-7550 400)(-7550 450);
WIRE 16 -1 (-7550 400)(-7550 250);
WIRE 16 -1 (-7400 400)(-7550 400);
WIRE 16 -1 (-7550 250)(-7400 250);
WIRE 16 -1 (-400 4200)(-350 4200);
WIRE 16 -1 (-400 4350)(-400 4200);
WIRE 16 -1 (-400 4150)(-400 4200);
WIRE 16 -1 (-450 4200)(-400 4200);
WIRE 16 -1 (-750 4150)(-400 4150);
WIRE 16 -1 (-450 4350)(-400 4350);
WIRE 16 -1 (-1550 1250)(-1550 1300);
WIRE 16 -1 (-6250 750)(-6250 700);
WIRE 16 -1 (-6450 2650)(-6600 2650);
WIRE 17 -1 (-7100 1325)(-7100 1275);
WIRE 17 -1 (-7100 1375)(-7100 1325);
WIRE 17 -1 (-7600 1425)(-7100 1425);
FORCEPROP 2 LAST SIG_NAME LPC_LAD_IO<3:0>
J 0
(-7535 1435);
DISPLAY 0.638298 (-7535 1435);
PAINT ORANGE (-7535 1435);
WIRE 17 -1 (-7100 1425)(-7100 1375);
WIRE 16 -1 (-1500 1800)(-550 1800);
FORCEPROP 2 LAST SIG_NAME RST_PLTRST_BUF_N
J 0
(-1035 1810);
DISPLAY 0.617021 (-1035 1810);
PAINT ORANGE (-1035 1810);
WIRE 16 -1 (-1350 2050)(-800 2050);
FORCEPROP 2 LAST SIG_NAME SPI_BMC_BT_CS_N
J 0
(-1310 2060);
DISPLAY 0.638298 (-1310 2060);
PAINT ORANGE (-1310 2060);
WIRE 16 -1 (-2550 2000)(-800 2000);
FORCEPROP 2 LAST SIG_NAME FM_MP_PS_REDUNDANT_LOST_N
J 0
(-2335 2010);
DISPLAY 0.638298 (-2335 2010);
PAINT ORANGE (-2335 2010);
WIRE 3 682 (-1200 1750)(-1100 1750);
WIRE 16 -1 (-2550 1600)(-1300 1600);
FORCEPROP 0 LAST CDS_PHYS_NET_NAME FM_POST_CARD_PRES_BMC_N
J 0
(-2400 1642);
PAINT MONO (-2400 1642);
DISPLAY INVISIBLE (-2400 1642);
FORCEPROP 2 LAST SIG_NAME FM_POST_CARD_PRES_BMC_N
J 0
(-2335 1610);
DISPLAY 0.638298 (-2335 1610);
PAINT ORANGE (-2335 1610);
WIRE 16 -1 (-1550 1500)(-1550 1650);
WIRE 16 -1 (-1300 1650)(-1550 1650);
WIRE 16 -1 (-2550 1650)(-1550 1650);
FORCEPROP 2 LAST SIG_NAME FM_PE_BMC_WAKE_N
J 0
(-2335 1660);
DISPLAY 0.638298 (-2335 1660);
PAINT ORANGE (-2335 1660);
WIRE 16 -1 (-2550 1900)(-1525 1900);
FORCEPROP 0 LAST CDS_PHYS_NET_NAME BMC_PRDY_N
J 0
(-2400 1939);
PAINT MONO (-2400 1939);
DISPLAY INVISIBLE (-2400 1939);
FORCEPROP 2 LAST SIG_NAME BMC_PRDY_N
J 0
(-2335 1910);
DISPLAY 0.638298 (-2335 1910);
PAINT ORANGE (-2335 1910);
WIRE 16 -1 (-2550 1800)(-1700 1800);
FORCEPROP 2 LAST SIG_NAME RST_BMC_PLTRST_BUF_N
J 0
(-2335 1810);
DISPLAY 0.638298 (-2335 1810);
PAINT ORANGE (-2335 1810);
FORCEPROP 2 LASTPROP $XRERR UNIQUE?
J 0
(-2575 1810);
DISPLAY 0.638298 (-2575 1810);
PAINT MONO (-2575 1810);
DISPLAY INVISIBLE (-2575 1810);
WIRE 16 -1 (-2550 1850)(-1525 1850);
FORCEPROP 2 LAST SIG_NAME XDP_PRESENT_N
J 0
(-2335 1860);
DISPLAY 0.638298 (-2335 1860);
PAINT ORANGE (-2335 1860);
WIRE 16 -1 (-7050 2050)(-5500 2050);
FORCEPROP 2 LAST SIG_NAME BMC_VGA_VSYNC
J 0
(-6985 2060);
DISPLAY 0.638298 (-6985 2060);
PAINT ORANGE (-6985 2060);
WIRE 3 2175 (-7500 1950)(-6200 1950);
WIRE 3 2175 (-6200 2300)(-6200 1950);
WIRE 3 2175 (-7500 2300)(-7500 1950);
WIRE 3 2175 (-7500 2300)(-6200 2300);
WIRE 16 -1 (-6250 950)(-6250 1500);
WIRE 16 -1 (-5500 1500)(-6250 1500);
WIRE 16 -1 (-7050 1500)(-6250 1500);
FORCEPROP 2 LAST SIG_NAME CLK_24M_BMC_LPC
J 0
(-6710 1510);
DISPLAY 0.638298 (-6710 1510);
PAINT ORANGE (-6710 1510);
WIRE 3 2175 (-7800 150)(-6250 150);
WIRE 3 2175 (-6250 600)(-6250 150);
WIRE 3 2175 (-7800 600)(-7800 150);
WIRE 3 2175 (-7800 600)(-6250 600);
WIRE 3 682 (-7650 4500)(-7650 4750);
WIRE 3 682 (-7050 4500)(-7650 4500);
WIRE 16 -1 (-6450 4100)(-5375 4100);
FORCEPROP 2 LAST SIG_NAME BMC_STRAP_BIT18
J 0
(-6385 4110);
DISPLAY 0.638298 (-6385 4110);
PAINT ORANGE (-6385 4110);
WIRE 16 -1 (-5375 3900)(-6800 3900);
FORCEPROP 2 LAST SIG_NAME FM_BMC_NMI_N_R
J 0
(-6385 3910);
DISPLAY 0.638298 (-6385 3910);
PAINT ORANGE (-6385 3910);
FORCEPROP 2 LASTPROP $XRERR UNIQUE?
J 0
(-6625 3910);
DISPLAY 0.638298 (-6625 3910);
PAINT MONO (-6625 3910);
DISPLAY INVISIBLE (-6625 3910);
WIRE 16 -1 (-7500 3900)(-7000 3900);
FORCEPROP 2 LAST SIG_NAME FM_BMC_NMI_N
J 0
(-7435 3910);
DISPLAY 0.638298 (-7435 3910);
PAINT ORANGE (-7435 3910);
WIRE 16 -1 (-6450 4600)(-5375 4600);
FORCEPROP 2 LAST SIG_NAME IRQ_LOM_ALERT_N
J 0
(-6385 4610);
DISPLAY 0.638298 (-6385 4610);
PAINT ORANGE (-6385 4610);
WIRE 16 -1 (-6450 4550)(-5375 4550);
FORCEPROP 0 LAST CDS_PHYS_NET_NAME BMC_UV_HIGH_SET
J 0
(-6285 4592);
PAINT MONO (-6285 4592);
DISPLAY INVISIBLE (-6285 4592);
FORCEPROP 2 LAST SIG_NAME UV_HIGH_SET
J 0
(-6385 4560);
DISPLAY 0.638298 (-6385 4560);
PAINT ORANGE (-6385 4560);
WIRE 16 -1 (-6450 4500)(-5375 4500);
FORCEPROP 2 LAST SIG_NAME PECI_SEL
J 0
(-6385 4510);
DISPLAY 0.638298 (-6385 4510);
PAINT ORANGE (-6385 4510);
WIRE 16 -1 (-5375 4450)(-6450 4450);
FORCEPROP 0 LAST CDS_PHYS_NET_NAME FM_TPM_PRES_N
J 0
(-6310 4492);
PAINT MONO (-6310 4492);
DISPLAY INVISIBLE (-6310 4492);
FORCEPROP 2 LAST SIG_NAME FM_TPM_PRES_N
J 0
(-6385 4460);
DISPLAY 0.638298 (-6385 4460);
PAINT ORANGE (-6385 4460);
WIRE 16 -1 (-7050 2600)(-5500 2600);
FORCEPROP 2 LAST SIG_NAME RST_BMC_EXTRST_N
J 0
(-6185 2610);
DISPLAY 0.638298 (-6185 2610);
PAINT ORANGE (-6185 2610);
WIRE 16 -1 (-7050 2500)(-6450 2500);
FORCEPROP 2 LAST SIG_NAME SPI_BMC_BT_DO
J 0
(-6985 2510);
DISPLAY 0.638298 (-6985 2510);
PAINT ORANGE (-6985 2510);
WIRE 16 -1 (-7050 2450)(-5500 2450);
FORCEPROP 2 LAST SIG_NAME SPI_BMC_BT_DI
J 0
(-6185 2460);
DISPLAY 0.638298 (-6185 2460);
PAINT ORANGE (-6185 2460);
WIRE 16 -1 (-6450 4650)(-5375 4650);
FORCEPROP 2 LAST SIG_NAME FM_BIOS_POST_CMPLT_N
J 0
(-6385 4660);
DISPLAY 0.638298 (-6385 4660);
PAINT ORANGE (-6385 4660);
WIRE 16 -1 (-6450 4000)(-5375 4000);
FORCEPROP 2 LAST SIG_NAME IRQ_BMC_PCH_SCI_LPC_N
J 0
(-6385 4010);
DISPLAY 0.638298 (-6385 4010);
PAINT ORANGE (-6385 4010);
WIRE 16 -1 (-6450 3950)(-5375 3950);
FORCEPROP 0 LAST CDS_PHYS_NET_NAME IRQ_PVDDQ_DEF_VRHOT_LVT3_N
J 0
(-6200 3992);
PAINT MONO (-6200 3992);
DISPLAY INVISIBLE (-6200 3992);
FORCEPROP 0 LAST $PHYS_NET_NAME IRQ_PVDDQ_DEF_VRHOT_LVT3_N
J 0
(-6200 4039);
PAINT MONO (-6200 4039);
DISPLAY INVISIBLE (-6200 4039);
FORCEPROP 2 LAST SIG_NAME IRQ_PVDDQ_DEF_VRHOT_LVT3_N
J 0
(-6385 3960);
DISPLAY 0.638298 (-6385 3960);
PAINT ORANGE (-6385 3960);
WIRE 16 -1 (-6450 3850)(-5375 3850);
FORCEPROP 0 LAST CDS_PHYS_NET_NAME FM_BMC_CPLD_GPO
J 0
(-6450 3889);
PAINT MONO (-6450 3889);
DISPLAY INVISIBLE (-6450 3889);
FORCEPROP 0 LAST PHYS_NET_NAME FM_BMC_CPLD_GPO
J 0
(-6450 3936);
PAINT MONO (-6450 3936);
DISPLAY INVISIBLE (-6450 3936);
FORCEPROP 2 LAST SIG_NAME FM_BMC_CPLD_GPO
J 0
(-6385 3860);
DISPLAY 0.638298 (-6385 3860);
PAINT ORANGE (-6385 3860);
WIRE 16 -1 (-6450 3400)(-5375 3400);
FORCEPROP 2 LAST SIG_NAME FM_THROTTLE_N
J 0
(-6385 3410);
DISPLAY 0.638298 (-6385 3410);
PAINT ORANGE (-6385 3410);
WIRE 16 -1 (-7050 2000)(-5500 2000);
FORCEPROP 2 LAST SIG_NAME BMC_VGA_HSYNC
J 0
(-6985 2010);
DISPLAY 0.638298 (-6985 2010);
PAINT ORANGE (-6985 2010);
WIRE 16 682 (-7900 1525)(-7900 1850);
WIRE 16 682 (-6200 1850)(-7900 1850);
WIRE 16 682 (-7900 1525)(-6200 1525);
WIRE 16 682 (-6200 1525)(-6200 1850);
WIRE 16 -1 (-7050 1650)(-6450 1650);
FORCEPROP 2 LAST SIG_NAME IRQ_LPC_SERIRQ_N
J 0
(-6985 1660);
DISPLAY 0.638298 (-6985 1660);
PAINT ORANGE (-6985 1660);
WIRE 3 682 (-7900 1150)(-7900 1025);
WIRE 3 682 (-7250 1150)(-7900 1150);
WIRE 16 -1 (-5750 1450)(-5500 1450);
WIRE 16 -1 (-5750 1400)(-5750 1450);
WIRE 16 -1 (-6750 1400)(-5750 1400);
FORCEPROP 2 LAST SIG_NAME LPC_LAD3_IO3_R
J 0
(-6185 1410);
DISPLAY 0.638298 (-6185 1410);
PAINT ORANGE (-6185 1410);
FORCEPROP 2 LASTPROP $XRERR UNIQUE?
J 0
(-6425 1410);
DISPLAY 0.638298 (-6425 1410);
PAINT MONO (-6425 1410);
DISPLAY INVISIBLE (-6425 1410);
WIRE 16 -1 (-5600 1300)(-5500 1300);
WIRE 16 -1 (-5600 1250)(-6750 1250);
FORCEPROP 2 LAST SIG_NAME LPC_LAD0_IO0_R
J 0
(-6185 1260);
DISPLAY 0.638298 (-6185 1260);
PAINT ORANGE (-6185 1260);
FORCEPROP 2 LASTPROP $XRERR UNIQUE?
J 0
(-6425 1260);
DISPLAY 0.638298 (-6425 1260);
PAINT MONO (-6425 1260);
DISPLAY INVISIBLE (-6425 1260);
WIRE 16 -1 (-5600 1250)(-5600 1300);
WIRE 16 -1 (-5650 1350)(-5500 1350);
WIRE 16 -1 (-5650 1300)(-6750 1300);
FORCEPROP 2 LAST SIG_NAME LPC_LAD1_IO1_R
J 0
(-6185 1310);
DISPLAY 0.638298 (-6185 1310);
PAINT ORANGE (-6185 1310);
FORCEPROP 2 LASTPROP $XRERR UNIQUE?
J 0
(-6425 1310);
DISPLAY 0.638298 (-6425 1310);
PAINT MONO (-6425 1310);
DISPLAY INVISIBLE (-6425 1310);
WIRE 16 -1 (-5650 1300)(-5650 1350);
WIRE 16 -1 (-5500 1100)(-6850 1100);
FORCEPROP 2 LAST SIG_NAME FM_OCP_MEZZA_PRES
J 0
(-6785 1110);
DISPLAY 0.638298 (-6785 1110);
PAINT ORANGE (-6785 1110);
WIRE 16 -1 (-5500 1150)(-6850 1150);
FORCEPROP 0 LAST CDS_PHYS_NET_NAME BMC_SELF_HW_RST
J 0
(-6685 1192);
PAINT MONO (-6685 1192);
DISPLAY INVISIBLE (-6685 1192);
FORCEPROP 2 LAST SIG_NAME BMC_SELF_HW_RST
J 0
(-6785 1160);
DISPLAY 0.638298 (-6785 1160);
PAINT ORANGE (-6785 1160);
WIRE 16 -1 (-6850 1050)(-5500 1050);
FORCEPROP 0 LAST CDS_PHYS_NET_NAME IRQ_HSC_FAULT_N
J 0
(-5500 1089);
PAINT MONO (-5500 1089);
DISPLAY INVISIBLE (-5500 1089);
FORCEPROP 2 LAST SIG_NAME IRQ_HSC_FAULT_N
J 0
(-6785 1060);
DISPLAY 0.638298 (-6785 1060);
PAINT ORANGE (-6785 1060);
FORCEPROP 0 LAST PHYS_NET_NAME IRQ_HSC_FAULT_N
J 0
(-5500 1136);
PAINT MONO (-5500 1136);
DISPLAY INVISIBLE (-5500 1136);
WIRE 16 -1 (-6250 1550)(-5500 1550);
FORCEPROP 2 LAST SIG_NAME LPC_LFRAME_N_CS0_R_N
J 0
(-6185 1560);
DISPLAY 0.638298 (-6185 1560);
PAINT ORANGE (-6185 1560);
FORCEPROP 2 LASTPROP $XRERR UNIQUE?
J 0
(-6425 1560);
DISPLAY 0.638298 (-6425 1560);
PAINT MONO (-6425 1560);
DISPLAY INVISIBLE (-6425 1560);
WIRE 16 -1 (-5700 1400)(-5500 1400);
WIRE 16 -1 (-5700 1350)(-6750 1350);
FORCEPROP 2 LAST SIG_NAME LPC_LAD2_IO2_R
J 0
(-6185 1360);
DISPLAY 0.638298 (-6185 1360);
PAINT ORANGE (-6185 1360);
FORCEPROP 2 LASTPROP $XRERR UNIQUE?
J 0
(-6425 1360);
DISPLAY 0.638298 (-6425 1360);
PAINT MONO (-6425 1360);
DISPLAY INVISIBLE (-6425 1360);
WIRE 16 -1 (-5700 1350)(-5700 1400);
WIRE 16 -1 (-5700 1600)(-5500 1600);
WIRE 16 -1 (-5700 1650)(-5700 1600);
WIRE 16 -1 (-6250 1650)(-5700 1650);
FORCEPROP 2 LAST SIG_NAME IRQ_LPC_SERIRQ_R
J 0
(-6185 1660);
DISPLAY 0.638298 (-6185 1660);
PAINT ORANGE (-6185 1660);
FORCEPROP 2 LASTPROP $XRERR UNIQUE?
J 0
(-6425 1660);
DISPLAY 0.638298 (-6425 1660);
PAINT MONO (-6425 1660);
DISPLAY INVISIBLE (-6425 1660);
WIRE 16 -1 (-5650 1650)(-5500 1650);
WIRE 16 -1 (-5650 1750)(-6250 1750);
FORCEPROP 2 LAST SIG_NAME RST_BMC_LVC3_N
J 0
(-6185 1760);
DISPLAY 0.638298 (-6185 1760);
PAINT ORANGE (-6185 1760);
FORCEPROP 2 LASTPROP $XRERR UNIQUE?
J 0
(-6425 1760);
DISPLAY 0.638298 (-6425 1760);
PAINT MONO (-6425 1760);
DISPLAY INVISIBLE (-6425 1760);
WIRE 16 -1 (-5650 1750)(-5650 1650);
WIRE 16 -1 (-7050 2200)(-5500 2200);
FORCEPROP 2 LAST SIG_NAME I2C_BMC_VGA_DDC_SCL
J 0
(-6985 2210);
DISPLAY 0.638298 (-6985 2210);
PAINT ORANGE (-6985 2210);
WIRE 16 -1 (-7050 2250)(-5500 2250);
FORCEPROP 2 LAST SIG_NAME I2C_BMC_VGA_DDC_SDA
J 0
(-6985 2260);
DISPLAY 0.638298 (-6985 2260);
PAINT ORANGE (-6985 2260);
WIRE 16 -1 (-5500 2350)(-6250 2350);
FORCEPROP 2 LAST SIG_NAME SPI_BMC_BT_CLK_R
J 0
(-6185 2360);
DISPLAY 0.638298 (-6185 2360);
PAINT ORANGE (-6185 2360);
FORCEPROP 2 LASTPROP $XRERR UNIQUE?
J 0
(-6425 2360);
DISPLAY 0.638298 (-6425 2360);
PAINT MONO (-6425 2360);
DISPLAY INVISIBLE (-6425 2360);
WIRE 16 -1 (-6250 2650)(-5500 2650);
FORCEPROP 2 LAST SIG_NAME PD_SP_ENTEST
J 0
(-6185 2660);
DISPLAY 0.638298 (-6185 2660);
PAINT ORANGE (-6185 2660);
FORCEPROP 2 LASTPROP $XRERR UNIQUE?
J 0
(-6425 2660);
DISPLAY 0.638298 (-6425 2660);
PAINT MONO (-6425 2660);
DISPLAY INVISIBLE (-6425 2660);
WIRE 16 -1 (-6450 3450)(-5375 3450);
FORCEPROP 2 LAST SIG_NAME FM_BMC_READY_N
J 0
(-6385 3460);
DISPLAY 0.638298 (-6385 3460);
PAINT ORANGE (-6385 3460);
WIRE 16 -1 (-6450 3500)(-5375 3500);
FORCEPROP 2 LAST SIG_NAME IRQ_SML0_ALERT_N
J 0
(-6385 3510);
DISPLAY 0.638298 (-6385 3510);
PAINT ORANGE (-6385 3510);
WIRE 16 -1 (-6450 3550)(-5375 3550);
FORCEPROP 2 LAST SIG_NAME HSC_SMBUS_SWITCH_EN
J 0
(-6385 3560);
DISPLAY 0.638298 (-6385 3560);
PAINT ORANGE (-6385 3560);
WIRE 16 -1 (-5375 4150)(-6450 4150);
FORCEPROP 2 LAST SIG_NAME BMC_STRAP_BIT20
J 0
(-6385 4160);
DISPLAY 0.638298 (-6385 4160);
PAINT ORANGE (-6385 4160);
WIRE 16 -1 (-6450 4200)(-5375 4200);
FORCEPROP 2 LAST SIG_NAME BMC_STRAP_BIT27
J 0
(-6385 4210);
DISPLAY 0.638298 (-6385 4210);
PAINT ORANGE (-6385 4210);
WIRE 16 -1 (-6450 4300)(-5375 4300);
FORCEPROP 2 LAST SIG_NAME FM_CPU1_SKTOCC_LVT3_N
J 0
(-6385 4310);
DISPLAY 0.638298 (-6385 4310);
PAINT ORANGE (-6385 4310);
WIRE 16 -1 (-6450 4400)(-5375 4400);
FORCEPROP 2 LAST SIG_NAME FP_PWR_ID_LED_N
J 0
(-6385 4410);
DISPLAY 0.638298 (-6385 4410);
PAINT ORANGE (-6385 4410);
WIRE 16 -1 (-6450 4350)(-5375 4350);
FORCEPROP 2 LAST SIG_NAME IRQ_SML1_PMBUS_ALERT_N
J 0
(-6385 4360);
DISPLAY 0.638298 (-6385 4360);
PAINT ORANGE (-6385 4360);
WIRE 16 -1 (-5375 4050)(-6450 4050);
FORCEPROP 2 LAST SIG_NAME BMC_STRAP_BIT17
J 0
(-6385 4060);
DISPLAY 0.638298 (-6385 4060);
PAINT ORANGE (-6385 4060);
WIRE 16 -1 (-6450 3750)(-5375 3750);
FORCEPROP 2 LAST SIG_NAME GPIOS7
J 0
(-6385 3760);
DISPLAY 0.638298 (-6385 3760);
PAINT ORANGE (-6385 3760);
WIRE 16 -1 (-5375 3700)(-6450 3700);
FORCEPROP 2 LAST SIG_NAME BMC_STRAP_BIT5
J 0
(-6385 3710);
DISPLAY 0.638298 (-6385 3710);
PAINT ORANGE (-6385 3710);
WIRE 16 -1 (-6450 3600)(-5375 3600);
FORCEPROP 0 LAST CDS_PHYS_NET_NAME H_CPU0_MEMDEF_MEMHOT_LVT3_BMC_N
J 0
(-6125 3639);
PAINT MONO (-6125 3639);
DISPLAY INVISIBLE (-6125 3639);
FORCEPROP 2 LAST SIG_NAME BMC_STRAP_BIT3
J 0
(-6385 3610);
DISPLAY 0.638298 (-6385 3610);
PAINT ORANGE (-6385 3610);
WIRE 16 -1 (-2550 2050)(-1550 2050);
FORCEPROP 2 LAST SIG_NAME SPI_BMC_BT_CS_R_N
J 0
(-2335 2060);
DISPLAY 0.638298 (-2335 2060);
PAINT ORANGE (-2335 2060);
FORCEPROP 2 LASTPROP $XRERR UNIQUE?
J 0
(-2575 2060);
DISPLAY 0.638298 (-2575 2060);
PAINT MONO (-2575 2060);
DISPLAY INVISIBLE (-2575 2060);
WIRE 16 -1 (-700 4200)(-2375 4200);
FORCEPROP 2 LAST SIG_NAME A_USB2AVRES
J 0
(-2185 4210);
DISPLAY 0.638298 (-2185 4210);
PAINT ORANGE (-2185 4210);
FORCEPROP 2 LASTPROP $XRERR UNIQUE?
J 0
(-2425 4210);
DISPLAY 0.638298 (-2425 4210);
PAINT MONO (-2425 4210);
DISPLAY INVISIBLE (-2425 4210);
WIRE 16 -1 (-650 4200)(-700 4200);
WIRE 16 -1 (-700 4350)(-700 4200);
WIRE 16 -1 (-650 4350)(-700 4350);
WIRE 16 -1 (-2550 1950)(-1525 1950);
FORCEPROP 0 LAST CDS_PHYS_NET_NAME BMC_TCK_MUX_SEL
J 0
(-2400 1989);
PAINT MONO (-2400 1989);
DISPLAY INVISIBLE (-2400 1989);
FORCEPROP 2 LAST SIG_NAME BMC_TCK_MUX_SEL
J 0
(-2335 1960);
DISPLAY 0.638298 (-2335 1960);
PAINT ORANGE (-2335 1960);
WIRE 16 -1 (-2550 2550)(-1300 2550);
FORCEPROP 2 LAST SIG_NAME FM_BMC_HEARTBEAT_N
J 0
(-2335 2560);
DISPLAY 0.638298 (-2335 2560);
PAINT ORANGE (-2335 2560);
WIRE 16 -1 (-1300 2650)(-2550 2650);
FORCEPROP 2 LAST SIG_NAME BMC_M_RST_N
J 0
(-2335 2660);
DISPLAY 0.638298 (-2335 2660);
PAINT ORANGE (-2335 2660);
WIRE 16 -1 (-1300 2600)(-2550 2600);
FORCEPROP 2 LAST SIG_NAME BMC_M_MALERT_N
J 0
(-2335 2610);
DISPLAY 0.638298 (-2335 2610);
PAINT ORANGE (-2335 2610);
WIRE 3 682 (-850 1850)(-900 1850);
WIRE 3 682 (-850 1900)(-850 1850);
WIRE 3 682 (-850 1900)(-800 1900);
WIRE 3 682 (-900 1950)(-850 1950);
WIRE 3 682 (-850 1950)(-850 1900);
WIRE 3 682 (-850 4550)(-850 4300);
WIRE 3 682 (-100 4550)(-850 4550);
WIRE 3 682 (-850 4300)(-100 4300);
WIRE 3 682 (-100 4300)(-100 4550);
WIRE 3 682 (-2250 4800)(-2250 4250);
WIRE 3 682 (-1100 4800)(-2250 4800);
WIRE 3 682 (-2250 4250)(-1100 4250);
WIRE 3 682 (-1100 4250)(-1100 4800);
WIRE 16 -1 (-2375 4150)(-950 4150);
FORCEPROP 2 LAST SIG_NAME A_USB2BVRES
J 0
(-2185 4160);
DISPLAY 0.638298 (-2185 4160);
PAINT ORANGE (-2185 4160);
FORCEPROP 2 LASTPROP $XRERR UNIQUE?
J 0
(-2425 4160);
DISPLAY 0.638298 (-2425 4160);
PAINT MONO (-2425 4160);
DISPLAY INVISIBLE (-2425 4160);
WIRE 16 -1 (-2375 4050)(-1500 4050);
FORCEPROP 2 LAST SIG_NAME LED_POSTCODE_7
J 0
(-2185 4060);
DISPLAY 0.638298 (-2185 4060);
PAINT ORANGE (-2185 4060);
WIRE 16 -1 (-2375 3900)(-1500 3900);
FORCEPROP 2 LAST SIG_NAME LED_POSTCODE_4
J 0
(-2185 3910);
DISPLAY 0.638298 (-2185 3910);
PAINT ORANGE (-2185 3910);
WIRE 16 -1 (-2375 3700)(-1500 3700);
FORCEPROP 2 LAST SIG_NAME LED_POSTCODE_0
J 0
(-2185 3710);
DISPLAY 0.638298 (-2185 3710);
PAINT ORANGE (-2185 3710);
WIRE 16 -1 (-2375 3750)(-1500 3750);
FORCEPROP 2 LAST SIG_NAME LED_POSTCODE_1
J 0
(-2185 3760);
DISPLAY 0.638298 (-2185 3760);
PAINT ORANGE (-2185 3760);
WIRE 16 -1 (-2375 3850)(-1500 3850);
FORCEPROP 2 LAST SIG_NAME LED_POSTCODE_3
J 0
(-2185 3860);
DISPLAY 0.638298 (-2185 3860);
PAINT ORANGE (-2185 3860);
WIRE 16 -1 (-2375 3950)(-1500 3950);
FORCEPROP 2 LAST SIG_NAME LED_POSTCODE_5
J 0
(-2185 3960);
DISPLAY 0.638298 (-2185 3960);
PAINT ORANGE (-2185 3960);
WIRE 16 -1 (-2375 4300)(-1500 4300);
FORCEPROP 2 LAST SIG_NAME USB_PCH_BMC_P4_DN
J 0
(-2185 4310);
DISPLAY 0.638298 (-2185 4310);
PAINT ORANGE (-2185 4310);
WIRE 3 682 (-1600 4750)(-1600 4400);
WIRE 3 682 (-1550 4750)(-1600 4750);
WIRE 3 682 (-1600 4400)(-1550 4400);
WIRE 3 682 (-1550 4400)(-1550 4750);
WIRE 16 -1 (-7050 1750)(-6450 1750);
FORCEPROP 2 LAST SIG_NAME RST_PLTRST_BUF_N
J 0
(-6985 1760);
DISPLAY 0.638298 (-6985 1760);
PAINT ORANGE (-6985 1760);
WIRE 16 -1 (-7050 1550)(-6450 1550);
FORCEPROP 2 LAST SIG_NAME LPC_LFRAME_N_CS0_N
J 0
(-6985 1560);
DISPLAY 0.638298 (-6985 1560);
PAINT ORANGE (-6985 1560);
WIRE 16 -1 (-7200 400)(-6300 400);
FORCEPROP 2 LAST SIG_NAME I2C_BMC_VGA_DDC_SCL
J 0
(-6985 410);
DISPLAY 0.638298 (-6985 410);
PAINT ORANGE (-6985 410);
FORCEPROP 2 LASTPROP $XR0 146 
J 0
(-6240 400);
DISPLAY 0.638298 (-6240 400);
PAINT MONO (-6240 400);
FORCEPROP 2 LASTPROP $XR1 252 
J 0
(-6120 400);
DISPLAY 0.638298 (-6120 400);
PAINT MONO (-6120 400);
WIRE 16 -1 (-7200 250)(-6300 250);
FORCEPROP 2 LAST SIG_NAME I2C_BMC_VGA_DDC_SDA
J 0
(-6985 260);
DISPLAY 0.638298 (-6985 260);
PAINT ORANGE (-6985 260);
FORCEPROP 2 LASTPROP $XR0 146 
J 0
(-6240 250);
DISPLAY 0.638298 (-6240 250);
PAINT MONO (-6240 250);
FORCEPROP 2 LASTPROP $XR1 252 
J 0
(-6120 250);
DISPLAY 0.638298 (-6120 250);
PAINT MONO (-6120 250);
WIRE 16 -1 (-6950 1250)(-7000 1250);
WIRE 16 -1 (-6950 1300)(-7000 1300);
WIRE 16 -1 (-6950 1350)(-7000 1350);
WIRE 16 -1 (-6950 1400)(-7000 1400);
WIRE 16 -1 (-2375 3800)(-1500 3800);
FORCEPROP 2 LAST SIG_NAME LED_POSTCODE_2
J 0
(-2185 3810);
DISPLAY 0.638298 (-2185 3810);
PAINT ORANGE (-2185 3810);
WIRE 16 -1 (-2375 4500)(-1500 4500);
FORCEPROP 2 LAST SIG_NAME USB2_PCH_BMC_P5_DP
J 0
(-2185 4510);
DISPLAY 0.638298 (-2185 4510);
PAINT ORANGE (-2185 4510);
WIRE 16 -1 (-2375 4450)(-1500 4450);
FORCEPROP 2 LAST SIG_NAME USB2_PCH_BMC_P5_DN
J 0
(-2185 4460);
DISPLAY 0.638298 (-2185 4460);
PAINT ORANGE (-2185 4460);
WIRE 16 -1 (-1500 4350)(-2375 4350);
FORCEPROP 2 LAST SIG_NAME USB_PCH_BMC_P4_DP
J 0
(-2185 4360);
DISPLAY 0.638298 (-2185 4360);
PAINT ORANGE (-2185 4360);
WIRE 16 -1 (-2375 4000)(-1500 4000);
FORCEPROP 2 LAST SIG_NAME LED_POSTCODE_6
J 0
(-2185 4010);
DISPLAY 0.638298 (-2185 4010);
PAINT ORANGE (-2185 4010);
WIRE 16 -1 (-5500 2500)(-6250 2500);
FORCEPROP 2 LAST SIG_NAME SPI_BMC_BT_DO_R
J 0
(-6185 2510);
DISPLAY 0.638298 (-6185 2510);
PAINT ORANGE (-6185 2510);
FORCEPROP 2 LASTPROP $XRERR UNIQUE?
J 0
(-6425 2510);
DISPLAY 0.638298 (-6425 2510);
PAINT MONO (-6425 2510);
DISPLAY INVISIBLE (-6425 2510);
WIRE 16 -1 (-7050 2350)(-6450 2350);
FORCEPROP 2 LAST SIG_NAME SPI_BMC_BT_CLK
J 0
(-6985 2360);
DISPLAY 0.638298 (-6985 2360);
PAINT ORANGE (-6985 2360);
WIRE 16 -1 (-7050 2400)(-5500 2400);
FORCEPROP 0 LAST CDS_PHYS_NET_NAME SPI_BMC_BT_CS1_N
J 0
(-6910 2442);
PAINT MONO (-6910 2442);
DISPLAY INVISIBLE (-6910 2442);
FORCEPROP 2 LAST SIG_NAME SPI_BMC_BT_CS0_N
J 0
(-6185 2410);
DISPLAY 0.638298 (-6185 2410);
PAINT ORANGE (-6185 2410);
DOT 1 (-850 1900);
DOT 1 (-7550 400);
DOT 1 (-6250 1500);
DOT 1 (-400 4200);
DOT 1 (-700 4200);
DOT 1 (-1550 1650);
FORCENOTE
TP FAB4 POP R25W184 20170505
(-1050 1675) 0;
DISPLAY LEFT (-1050 1675);
DISPLAY 0.638298 (-1050 1675);
PAINT RED (-1050 1675);
FORCENOTE
TP FAB3 RECONNECT 0922
(-775 1900) 0;
DISPLAY LEFT (-775 1900);
DISPLAY 0.638298 (-775 1900);
PAINT RED (-775 1900);
FORCENOTE
TP FAB3 RESERVE A RES 1004
(-1050 1725) 0;
DISPLAY LEFT (-1050 1725);
DISPLAY 0.638298 (-1050 1725);
PAINT RED (-1050 1725);
FORCENOTE
TP FAB4 CHANGE CONNECTION FROM BMC_SELF_HW_RST TO PECI_SEL 20170203
(-7900 4775) 0;
DISPLAY LEFT (-7900 4775);
DISPLAY 0.638298 (-7900 4775);
PAINT RED (-7900 4775);
FORCENOTE
TP FAB1 ADD NETS 1230
(-7000 2125) 0;
DISPLAY LEFT (-7000 2125);
DISPLAY 1.021277 (-7000 2125);
PAINT RED (-7000 2125);
FORCENOTE
TP FAB4 CHANGE CONNECTION FROM PECI_SEL TO BMC_SELF_HW_RST 20170203
(-7950 925) 0;
DISPLAY LEFT (-7950 925);
DISPLAY 0.638298 (-7950 925);
PAINT RED (-7950 925);
FORCENOTE
TP FAB1 ADD NET 0311
(-7950 975) 0;
DISPLAY LEFT (-7950 975);
DISPLAY 0.638298 (-7950 975);
PAINT RED (-7950 975);
FORCENOTE
TP FAB3 ADD CAP 0803
(-950 4550) 0;
DISPLAY LEFT (-950 4550);
DISPLAY 1.021277 (-950 4550);
PAINT RED (-950 4550);
FORCENOTE
TP FAB1 DELETE PU RES 0121
(-1500 4650) 0;
DISPLAY LEFT (-1500 4650);
DISPLAY 1.021277 (-1500 4650);
PAINT RED (-1500 4650);
FORCENOTE
TP FAB1 NOPOP R25W66 0331
(-6050 650) 0;
DISPLAY LEFT (-6050 650);
DISPLAY 1.021277 (-6050 650);
PAINT RED (-6050 650);
FORCENOTE
TP FAB1 ADD RES 1230
(-6200 175) 0;
DISPLAY LEFT (-6200 175);
DISPLAY 1.021277 (-6200 175);
PAINT RED (-6200 175);
FORCENOTE
TP FAB1 SWAP USB_P5 AND USB P4 0227
(-2250 4825) 0;
DISPLAY LEFT (-2250 4825);
DISPLAY 1.021277 (-2250 4825);
PAINT RED (-2250 4825);
QUIT
